G04*
G04 #@! TF.GenerationSoftware,Altium Limited,Altium Designer,22.4.2 (48)*
G04*
G04 Layer_Physical_Order=6*
G04 Layer_Color=16711680*
%FSLAX25Y25*%
%MOIN*%
G70*
G04*
G04 #@! TF.SameCoordinates,446674BB-F454-490D-8607-5140536C8ADF*
G04*
G04*
G04 #@! TF.FilePolarity,Positive*
G04*
G01*
G75*
%ADD10C,0.01000*%
%ADD18C,0.00800*%
%ADD21C,0.00500*%
%ADD72R,0.02800X0.16500*%
%ADD73R,0.02800X0.12600*%
%ADD149C,0.02000*%
%ADD153C,0.01200*%
%ADD157C,0.05906*%
%ADD158R,0.05906X0.05906*%
%ADD159C,0.07500*%
%ADD160C,0.05000*%
%ADD161C,0.09843*%
%ADD162C,0.02166*%
%ADD163C,0.06598*%
%ADD164C,0.08661*%
%ADD165R,0.07874X0.07874*%
%ADD166C,0.25000*%
%ADD167C,0.01600*%
%ADD168C,0.03200*%
%ADD169C,0.01400*%
%ADD170C,0.20000*%
%ADD171C,0.01968*%
%ADD172C,0.00500*%
%ADD173R,0.02520X0.02677*%
%ADD174C,0.07749*%
%ADD175R,0.07382X0.06791*%
G36*
X315016Y-7748D02*
X315610D01*
Y-7802D01*
X315827D01*
Y-7856D01*
X316043D01*
Y-7910D01*
X316205D01*
Y-7964D01*
X316313D01*
Y-8018D01*
X316475D01*
Y-8072D01*
X316583D01*
Y-8126D01*
X316691D01*
Y-8180D01*
X316800D01*
Y-8234D01*
X316854D01*
Y-8288D01*
X316962D01*
Y-8342D01*
X317016D01*
Y-8396D01*
X317124D01*
Y-8450D01*
X317178D01*
Y-8504D01*
X317232D01*
Y-8558D01*
X317286D01*
Y-8613D01*
X317340D01*
Y-8667D01*
X317394D01*
Y-8721D01*
X317448D01*
Y-8775D01*
X317502D01*
Y-8829D01*
X317557D01*
Y-8883D01*
X317611D01*
Y-8937D01*
X317665D01*
Y-8991D01*
X317719D01*
Y-9045D01*
X317773D01*
Y-9099D01*
X317827D01*
Y-9153D01*
Y-9207D01*
X317881D01*
Y-9261D01*
X317935D01*
Y-9315D01*
Y-9369D01*
X317989D01*
Y-9424D01*
X318043D01*
Y-9478D01*
Y-9532D01*
X318097D01*
Y-9586D01*
Y-9640D01*
X318151D01*
Y-9694D01*
Y-9748D01*
X318205D01*
Y-9802D01*
Y-9856D01*
X318259D01*
Y-9910D01*
Y-9964D01*
Y-10018D01*
X318313D01*
Y-10072D01*
Y-10126D01*
X318367D01*
Y-10180D01*
Y-10234D01*
Y-10289D01*
Y-10343D01*
X318422D01*
Y-10397D01*
Y-10451D01*
Y-10505D01*
Y-10559D01*
X318476D01*
Y-10613D01*
Y-10667D01*
Y-10721D01*
Y-10775D01*
Y-10829D01*
Y-10883D01*
Y-10937D01*
X318530D01*
Y-10991D01*
Y-11045D01*
Y-11099D01*
Y-11153D01*
Y-11208D01*
Y-11262D01*
Y-11316D01*
Y-11370D01*
Y-11424D01*
Y-11478D01*
Y-11532D01*
Y-11586D01*
Y-11640D01*
X318476D01*
Y-11694D01*
Y-11748D01*
Y-11802D01*
Y-11856D01*
Y-11910D01*
X318422D01*
Y-11964D01*
Y-12019D01*
Y-12072D01*
Y-12127D01*
Y-12181D01*
X318367D01*
Y-12235D01*
Y-12289D01*
Y-12343D01*
X318313D01*
Y-12397D01*
Y-12451D01*
Y-12505D01*
X318259D01*
Y-12559D01*
Y-12613D01*
Y-12667D01*
X318205D01*
Y-12721D01*
Y-12775D01*
X318151D01*
Y-12829D01*
Y-12883D01*
X318097D01*
Y-12937D01*
Y-12992D01*
X318043D01*
Y-13046D01*
X317989D01*
Y-13100D01*
Y-13154D01*
X317935D01*
Y-13208D01*
Y-13262D01*
X317881D01*
Y-13316D01*
X317827D01*
Y-13370D01*
X317773D01*
Y-13424D01*
Y-13478D01*
X317719D01*
Y-13532D01*
X317665D01*
Y-13586D01*
X317611D01*
Y-13640D01*
X317557D01*
Y-13694D01*
X317502D01*
Y-13748D01*
X317448D01*
Y-13803D01*
X317394D01*
Y-13857D01*
X317340D01*
Y-13911D01*
X317286D01*
Y-13965D01*
X317232D01*
Y-14019D01*
X317178D01*
Y-14073D01*
X317070D01*
Y-14127D01*
X317016D01*
Y-14181D01*
X316908D01*
Y-14235D01*
X316854D01*
Y-14289D01*
X316746D01*
Y-14343D01*
X316637D01*
Y-14397D01*
X316583D01*
Y-14451D01*
X316421D01*
Y-14505D01*
X316313D01*
Y-14559D01*
X316151D01*
Y-14614D01*
X315989D01*
Y-14668D01*
X315827D01*
Y-14722D01*
X315556D01*
Y-14776D01*
X310312D01*
Y-14722D01*
X310042D01*
Y-14668D01*
X309826D01*
Y-14614D01*
X309664D01*
Y-14559D01*
X309501D01*
Y-14505D01*
X309393D01*
Y-14451D01*
X309285D01*
Y-14397D01*
X309177D01*
Y-14343D01*
X309069D01*
Y-14289D01*
X308961D01*
Y-14235D01*
X308907D01*
Y-14181D01*
X308799D01*
Y-14127D01*
X308744D01*
Y-14073D01*
X308690D01*
Y-14019D01*
X308636D01*
Y-13965D01*
X308528D01*
Y-13911D01*
X308474D01*
Y-13857D01*
X308420D01*
Y-13803D01*
X308366D01*
Y-13748D01*
X308312D01*
Y-13694D01*
X308258D01*
Y-13640D01*
X308204D01*
Y-13586D01*
X308150D01*
Y-13532D01*
X308096D01*
Y-13478D01*
Y-13424D01*
X308042D01*
Y-13370D01*
X307987D01*
Y-13316D01*
X307933D01*
Y-13262D01*
Y-13208D01*
X307879D01*
Y-13154D01*
X307825D01*
Y-13100D01*
Y-13046D01*
X307771D01*
Y-12992D01*
Y-12937D01*
X307717D01*
Y-12883D01*
Y-12829D01*
X307663D01*
Y-12775D01*
Y-12721D01*
X307609D01*
Y-12667D01*
Y-12613D01*
X307555D01*
Y-12559D01*
Y-12505D01*
Y-12451D01*
X307501D01*
Y-12397D01*
Y-12343D01*
Y-12289D01*
X307447D01*
Y-12235D01*
Y-12181D01*
Y-12127D01*
X307393D01*
Y-12072D01*
Y-12019D01*
Y-11964D01*
Y-11910D01*
Y-11856D01*
X307339D01*
Y-11802D01*
Y-11748D01*
Y-11694D01*
Y-11640D01*
Y-11586D01*
Y-11532D01*
Y-11478D01*
Y-11424D01*
Y-11370D01*
X307285D01*
Y-11316D01*
Y-11262D01*
Y-11208D01*
Y-11153D01*
X307339D01*
Y-11099D01*
Y-11045D01*
Y-10991D01*
Y-10937D01*
Y-10883D01*
Y-10829D01*
Y-10775D01*
Y-10721D01*
Y-10667D01*
Y-10613D01*
X307393D01*
Y-10559D01*
Y-10505D01*
Y-10451D01*
Y-10397D01*
X307447D01*
Y-10343D01*
Y-10289D01*
Y-10234D01*
Y-10180D01*
X307501D01*
Y-10126D01*
Y-10072D01*
Y-10018D01*
X307555D01*
Y-9964D01*
Y-9910D01*
X307609D01*
Y-9856D01*
Y-9802D01*
Y-9748D01*
X307663D01*
Y-9694D01*
Y-9640D01*
X307717D01*
Y-9586D01*
X307771D01*
Y-9532D01*
Y-9478D01*
X307825D01*
Y-9424D01*
Y-9369D01*
X307879D01*
Y-9315D01*
X307933D01*
Y-9261D01*
Y-9207D01*
X307987D01*
Y-9153D01*
X308042D01*
Y-9099D01*
Y-9045D01*
X308096D01*
Y-8991D01*
X308150D01*
Y-8937D01*
X308204D01*
Y-8883D01*
X308258D01*
Y-8829D01*
X308312D01*
Y-8775D01*
X308366D01*
Y-8721D01*
X308420D01*
Y-8667D01*
X308474D01*
Y-8613D01*
X308528D01*
Y-8558D01*
X308582D01*
Y-8504D01*
X308636D01*
Y-8450D01*
X308744D01*
Y-8396D01*
X308799D01*
Y-8342D01*
X308907D01*
Y-8288D01*
X308961D01*
Y-8234D01*
X309069D01*
Y-8180D01*
X309177D01*
Y-8126D01*
X309231D01*
Y-8072D01*
X309393D01*
Y-8018D01*
X309501D01*
Y-7964D01*
X309664D01*
Y-7910D01*
X309772D01*
Y-7856D01*
X309988D01*
Y-7802D01*
X310258D01*
Y-7748D01*
X310799D01*
Y-7694D01*
X310853D01*
Y-7748D01*
X310907D01*
Y-7694D01*
X315016D01*
Y-7748D01*
D02*
G37*
G36*
X395298D02*
X395352D01*
Y-7802D01*
Y-7856D01*
Y-7910D01*
Y-7964D01*
Y-8018D01*
Y-8072D01*
Y-8126D01*
Y-8180D01*
Y-8234D01*
Y-8288D01*
Y-8342D01*
Y-8396D01*
Y-8450D01*
Y-8504D01*
Y-8558D01*
Y-8613D01*
Y-8667D01*
Y-8721D01*
Y-8775D01*
Y-8829D01*
Y-8883D01*
Y-8937D01*
Y-8991D01*
Y-9045D01*
Y-9099D01*
Y-9153D01*
Y-9207D01*
Y-9261D01*
Y-9315D01*
Y-9369D01*
Y-9424D01*
Y-9478D01*
Y-9532D01*
Y-9586D01*
Y-9640D01*
Y-9694D01*
Y-9748D01*
Y-9802D01*
Y-9856D01*
Y-9910D01*
Y-9964D01*
Y-10018D01*
Y-10072D01*
Y-10126D01*
Y-10180D01*
Y-10234D01*
Y-10289D01*
Y-10343D01*
Y-10397D01*
Y-10451D01*
Y-10505D01*
Y-10559D01*
Y-10613D01*
Y-10667D01*
Y-10721D01*
Y-10775D01*
Y-10829D01*
Y-10883D01*
Y-10937D01*
Y-10991D01*
Y-11045D01*
Y-11099D01*
Y-11153D01*
Y-11208D01*
Y-11262D01*
Y-11316D01*
Y-11370D01*
Y-11424D01*
Y-11478D01*
Y-11532D01*
Y-11586D01*
Y-11640D01*
Y-11694D01*
Y-11748D01*
Y-11802D01*
Y-11856D01*
Y-11910D01*
Y-11964D01*
Y-12019D01*
Y-12072D01*
Y-12127D01*
Y-12181D01*
Y-12235D01*
Y-12289D01*
Y-12343D01*
Y-12397D01*
Y-12451D01*
Y-12505D01*
Y-12559D01*
Y-12613D01*
Y-12667D01*
Y-12721D01*
Y-12775D01*
Y-12829D01*
Y-12883D01*
Y-12937D01*
Y-12992D01*
Y-13046D01*
Y-13100D01*
Y-13154D01*
Y-13208D01*
Y-13262D01*
Y-13316D01*
Y-13370D01*
Y-13424D01*
Y-13478D01*
Y-13532D01*
Y-13586D01*
Y-13640D01*
Y-13694D01*
Y-13748D01*
Y-13803D01*
Y-13857D01*
Y-13911D01*
Y-13965D01*
Y-14019D01*
Y-14073D01*
Y-14127D01*
Y-14181D01*
Y-14235D01*
Y-14289D01*
Y-14343D01*
Y-14397D01*
Y-14451D01*
Y-14505D01*
Y-14559D01*
Y-14614D01*
Y-14668D01*
Y-14722D01*
Y-14776D01*
Y-14830D01*
Y-14884D01*
Y-14938D01*
Y-14992D01*
Y-15046D01*
Y-15100D01*
Y-15154D01*
Y-15208D01*
Y-15262D01*
Y-15316D01*
Y-15370D01*
Y-15424D01*
Y-15478D01*
Y-15532D01*
Y-15587D01*
Y-15641D01*
Y-15695D01*
Y-15749D01*
Y-15803D01*
Y-15857D01*
Y-15911D01*
Y-15965D01*
Y-16019D01*
Y-16073D01*
Y-16127D01*
Y-16181D01*
Y-16235D01*
Y-16289D01*
Y-16343D01*
Y-16398D01*
Y-16452D01*
Y-16506D01*
Y-16560D01*
Y-16614D01*
Y-16668D01*
Y-16722D01*
Y-16776D01*
Y-16830D01*
Y-16884D01*
Y-16938D01*
Y-16992D01*
Y-17046D01*
Y-17100D01*
Y-17154D01*
Y-17208D01*
Y-17263D01*
Y-17317D01*
Y-17371D01*
Y-17425D01*
Y-17479D01*
Y-17533D01*
Y-17587D01*
Y-17641D01*
Y-17695D01*
Y-17749D01*
Y-17803D01*
Y-17857D01*
Y-17911D01*
Y-17965D01*
Y-18019D01*
Y-18073D01*
Y-18127D01*
Y-18181D01*
Y-18236D01*
Y-18290D01*
Y-18344D01*
Y-18398D01*
Y-18452D01*
Y-18506D01*
Y-18560D01*
Y-18614D01*
Y-18668D01*
Y-18722D01*
Y-18776D01*
Y-18830D01*
Y-18884D01*
Y-18938D01*
Y-18993D01*
Y-19047D01*
Y-19101D01*
Y-19155D01*
Y-19209D01*
Y-19263D01*
Y-19317D01*
Y-19371D01*
Y-19425D01*
Y-19479D01*
Y-19533D01*
Y-19587D01*
Y-19641D01*
Y-19695D01*
Y-19749D01*
Y-19803D01*
Y-19858D01*
Y-19911D01*
Y-19966D01*
Y-20020D01*
Y-20074D01*
Y-20128D01*
Y-20182D01*
Y-20236D01*
Y-20290D01*
Y-20344D01*
Y-20398D01*
Y-20452D01*
Y-20506D01*
Y-20560D01*
Y-20614D01*
Y-20668D01*
Y-20722D01*
Y-20776D01*
Y-20831D01*
Y-20885D01*
Y-20939D01*
Y-20993D01*
Y-21047D01*
Y-21101D01*
Y-21155D01*
Y-21209D01*
Y-21263D01*
Y-21317D01*
Y-21371D01*
Y-21425D01*
Y-21479D01*
Y-21533D01*
Y-21587D01*
Y-21642D01*
Y-21696D01*
Y-21750D01*
Y-21804D01*
Y-21858D01*
Y-21912D01*
Y-21966D01*
Y-22020D01*
Y-22074D01*
Y-22128D01*
Y-22182D01*
Y-22236D01*
Y-22290D01*
Y-22344D01*
Y-22398D01*
Y-22452D01*
Y-22506D01*
Y-22561D01*
Y-22615D01*
Y-22669D01*
Y-22723D01*
Y-22777D01*
Y-22831D01*
Y-22885D01*
Y-22939D01*
Y-22993D01*
Y-23047D01*
Y-23101D01*
Y-23155D01*
Y-23209D01*
Y-23263D01*
Y-23317D01*
Y-23371D01*
Y-23426D01*
Y-23480D01*
Y-23534D01*
Y-23588D01*
Y-23642D01*
Y-23696D01*
Y-23750D01*
Y-23804D01*
Y-23858D01*
Y-23912D01*
Y-23966D01*
Y-24020D01*
Y-24074D01*
Y-24128D01*
Y-24182D01*
Y-24237D01*
Y-24291D01*
Y-24345D01*
Y-24399D01*
Y-24453D01*
Y-24507D01*
Y-24561D01*
Y-24615D01*
Y-24669D01*
Y-24723D01*
Y-24777D01*
Y-24831D01*
Y-24885D01*
Y-24939D01*
Y-24993D01*
Y-25047D01*
Y-25102D01*
Y-25155D01*
Y-25210D01*
Y-25264D01*
Y-25318D01*
Y-25372D01*
Y-25426D01*
Y-25480D01*
Y-25534D01*
Y-25588D01*
Y-25642D01*
Y-25696D01*
Y-25750D01*
Y-25804D01*
Y-25858D01*
Y-25912D01*
Y-25967D01*
Y-26021D01*
Y-26075D01*
Y-26129D01*
Y-26183D01*
Y-26237D01*
Y-26291D01*
Y-26345D01*
Y-26399D01*
Y-26453D01*
Y-26507D01*
Y-26561D01*
Y-26615D01*
Y-26669D01*
Y-26723D01*
Y-26777D01*
Y-26831D01*
Y-26886D01*
Y-26940D01*
Y-26994D01*
Y-27048D01*
Y-27102D01*
Y-27156D01*
Y-27210D01*
Y-27264D01*
Y-27318D01*
Y-27372D01*
Y-27426D01*
Y-27480D01*
Y-27534D01*
Y-27588D01*
Y-27642D01*
Y-27696D01*
Y-27751D01*
Y-27805D01*
Y-27859D01*
Y-27913D01*
Y-27967D01*
Y-28021D01*
Y-28075D01*
Y-28129D01*
Y-28183D01*
Y-28237D01*
Y-28291D01*
Y-28345D01*
Y-28399D01*
Y-28453D01*
Y-28507D01*
Y-28561D01*
Y-28615D01*
Y-28670D01*
Y-28724D01*
Y-28778D01*
Y-28832D01*
Y-28886D01*
Y-28940D01*
Y-28994D01*
Y-29048D01*
Y-29102D01*
Y-29156D01*
Y-29210D01*
Y-29264D01*
Y-29318D01*
X390108D01*
Y-29372D01*
Y-29426D01*
Y-29480D01*
Y-29535D01*
Y-29589D01*
Y-29643D01*
Y-29697D01*
Y-29751D01*
Y-29805D01*
Y-29859D01*
Y-29913D01*
Y-29967D01*
Y-30021D01*
Y-30075D01*
Y-30129D01*
Y-30183D01*
Y-30237D01*
Y-30291D01*
Y-30345D01*
Y-30400D01*
Y-30454D01*
Y-30508D01*
Y-30562D01*
Y-30616D01*
Y-30670D01*
Y-30724D01*
Y-30778D01*
Y-30832D01*
Y-30886D01*
Y-30940D01*
Y-30994D01*
Y-31048D01*
Y-31102D01*
Y-31156D01*
Y-31211D01*
Y-31265D01*
Y-31319D01*
Y-31373D01*
Y-31427D01*
Y-31481D01*
Y-31535D01*
Y-31589D01*
Y-31643D01*
Y-31697D01*
Y-31751D01*
Y-31805D01*
Y-31859D01*
Y-31913D01*
Y-31967D01*
Y-32021D01*
Y-32076D01*
Y-32129D01*
Y-32184D01*
Y-32238D01*
Y-32292D01*
Y-32346D01*
Y-32400D01*
Y-32454D01*
Y-32508D01*
Y-32562D01*
Y-32616D01*
Y-32670D01*
Y-32724D01*
Y-32778D01*
Y-32832D01*
Y-32886D01*
Y-32941D01*
Y-32994D01*
Y-33049D01*
Y-33103D01*
Y-33157D01*
Y-33211D01*
Y-33265D01*
Y-33319D01*
Y-33373D01*
Y-33427D01*
Y-33481D01*
Y-33535D01*
Y-33589D01*
Y-33643D01*
Y-33697D01*
Y-33751D01*
Y-33806D01*
Y-33860D01*
Y-33914D01*
Y-33968D01*
Y-34022D01*
Y-34076D01*
Y-34130D01*
Y-34184D01*
Y-34238D01*
Y-34292D01*
Y-34346D01*
Y-34400D01*
Y-34454D01*
Y-34508D01*
Y-34562D01*
Y-34616D01*
Y-34670D01*
Y-34725D01*
Y-34779D01*
Y-34833D01*
Y-34887D01*
Y-34941D01*
Y-34995D01*
Y-35049D01*
Y-35103D01*
Y-35157D01*
Y-35211D01*
Y-35265D01*
X395298D01*
Y-35319D01*
X395352D01*
Y-35373D01*
Y-35427D01*
Y-35481D01*
Y-35535D01*
Y-35590D01*
Y-35644D01*
Y-35698D01*
Y-35752D01*
Y-35806D01*
Y-35860D01*
Y-35914D01*
Y-35968D01*
Y-36022D01*
Y-36076D01*
Y-36130D01*
Y-36184D01*
Y-36238D01*
Y-36292D01*
Y-36346D01*
Y-36400D01*
Y-36454D01*
Y-36509D01*
Y-36563D01*
Y-36617D01*
X390108D01*
Y-36671D01*
Y-36725D01*
Y-36779D01*
Y-36833D01*
Y-36887D01*
Y-36941D01*
Y-36995D01*
Y-37049D01*
Y-37103D01*
Y-37157D01*
Y-37211D01*
Y-37265D01*
Y-37319D01*
Y-37374D01*
Y-37428D01*
Y-37482D01*
Y-37536D01*
Y-37590D01*
Y-37644D01*
Y-37698D01*
Y-37752D01*
Y-37806D01*
Y-37860D01*
Y-37914D01*
Y-37968D01*
Y-38022D01*
Y-38076D01*
Y-38130D01*
Y-38184D01*
Y-38238D01*
Y-38293D01*
Y-38347D01*
Y-38401D01*
Y-38455D01*
Y-38509D01*
Y-38563D01*
Y-38617D01*
Y-38671D01*
Y-38725D01*
Y-38779D01*
Y-38833D01*
Y-38887D01*
Y-38941D01*
Y-38995D01*
Y-39050D01*
Y-39103D01*
Y-39158D01*
Y-39212D01*
Y-39266D01*
Y-39320D01*
Y-39374D01*
Y-39428D01*
Y-39482D01*
Y-39536D01*
Y-39590D01*
Y-39644D01*
Y-39698D01*
Y-39752D01*
Y-39806D01*
Y-39860D01*
Y-39915D01*
Y-39968D01*
Y-40023D01*
Y-40077D01*
Y-40131D01*
Y-40185D01*
Y-40239D01*
Y-40293D01*
Y-40347D01*
Y-40401D01*
Y-40455D01*
Y-40509D01*
Y-40563D01*
Y-40617D01*
Y-40671D01*
Y-40725D01*
Y-40780D01*
Y-40834D01*
Y-40888D01*
Y-40942D01*
Y-40996D01*
Y-41050D01*
Y-41104D01*
Y-41158D01*
Y-41212D01*
Y-41266D01*
Y-41320D01*
Y-41374D01*
Y-41428D01*
Y-41482D01*
Y-41536D01*
Y-41590D01*
Y-41644D01*
Y-41699D01*
Y-41753D01*
Y-41807D01*
Y-41861D01*
Y-41915D01*
Y-41969D01*
Y-42023D01*
Y-42077D01*
Y-42131D01*
Y-42185D01*
Y-42239D01*
Y-42293D01*
Y-42347D01*
Y-42401D01*
Y-42455D01*
Y-42509D01*
Y-42564D01*
Y-42618D01*
X395352D01*
Y-42672D01*
Y-42726D01*
Y-42780D01*
Y-42834D01*
Y-42888D01*
Y-42942D01*
Y-42996D01*
Y-43050D01*
Y-43104D01*
Y-43158D01*
Y-43212D01*
Y-43266D01*
Y-43320D01*
Y-43374D01*
Y-43429D01*
Y-43483D01*
Y-43537D01*
Y-43591D01*
Y-43645D01*
Y-43699D01*
Y-43753D01*
Y-43807D01*
Y-43861D01*
Y-43915D01*
X395298D01*
Y-43969D01*
X390108D01*
Y-44023D01*
Y-44077D01*
Y-44131D01*
Y-44185D01*
Y-44239D01*
Y-44293D01*
Y-44348D01*
Y-44402D01*
Y-44456D01*
Y-44510D01*
Y-44564D01*
Y-44618D01*
Y-44672D01*
Y-44726D01*
Y-44780D01*
Y-44834D01*
Y-44888D01*
Y-44942D01*
Y-44996D01*
Y-45050D01*
Y-45104D01*
Y-45158D01*
Y-45213D01*
Y-45267D01*
Y-45321D01*
Y-45375D01*
Y-45429D01*
Y-45483D01*
Y-45537D01*
Y-45591D01*
Y-45645D01*
Y-45699D01*
Y-45753D01*
Y-45807D01*
Y-45861D01*
Y-45915D01*
Y-45969D01*
Y-46023D01*
Y-46077D01*
Y-46132D01*
Y-46186D01*
Y-46240D01*
Y-46294D01*
Y-46348D01*
Y-46402D01*
Y-46456D01*
Y-46510D01*
Y-46564D01*
Y-46618D01*
Y-46672D01*
Y-46726D01*
Y-46780D01*
Y-46834D01*
Y-46889D01*
Y-46942D01*
Y-46997D01*
Y-47051D01*
Y-47105D01*
Y-47159D01*
Y-47213D01*
Y-47267D01*
Y-47321D01*
Y-47375D01*
Y-47429D01*
Y-47483D01*
Y-47537D01*
Y-47591D01*
Y-47645D01*
Y-47699D01*
Y-47754D01*
Y-47807D01*
Y-47862D01*
Y-47916D01*
Y-47970D01*
Y-48024D01*
Y-48078D01*
Y-48132D01*
Y-48186D01*
Y-48240D01*
Y-48294D01*
Y-48348D01*
Y-48402D01*
Y-48456D01*
Y-48510D01*
Y-48564D01*
Y-48619D01*
Y-48673D01*
Y-48727D01*
Y-48781D01*
Y-48835D01*
Y-48889D01*
Y-48943D01*
Y-48997D01*
Y-49051D01*
Y-49105D01*
Y-49159D01*
Y-49213D01*
Y-49267D01*
Y-49321D01*
Y-49375D01*
Y-49429D01*
Y-49483D01*
Y-49538D01*
Y-49592D01*
Y-49646D01*
Y-49700D01*
Y-49754D01*
Y-49808D01*
Y-49862D01*
Y-49916D01*
X395352D01*
Y-49970D01*
Y-50024D01*
Y-50078D01*
Y-50132D01*
Y-50186D01*
Y-50240D01*
Y-50294D01*
Y-50348D01*
Y-50402D01*
Y-50457D01*
Y-50511D01*
Y-50565D01*
Y-50619D01*
Y-50673D01*
Y-50727D01*
Y-50781D01*
Y-50835D01*
Y-50889D01*
Y-50943D01*
Y-50997D01*
Y-51051D01*
Y-51105D01*
Y-51159D01*
Y-51213D01*
Y-51267D01*
X390108D01*
Y-51322D01*
Y-51376D01*
Y-51430D01*
Y-51484D01*
Y-51538D01*
Y-51592D01*
Y-51646D01*
Y-51700D01*
Y-51754D01*
Y-51808D01*
Y-51862D01*
Y-51916D01*
Y-51970D01*
Y-52024D01*
Y-52078D01*
Y-52132D01*
Y-52187D01*
Y-52241D01*
Y-52295D01*
Y-52349D01*
Y-52403D01*
Y-52457D01*
Y-52511D01*
Y-52565D01*
Y-52619D01*
Y-52673D01*
Y-52727D01*
Y-52781D01*
Y-52835D01*
Y-52889D01*
Y-52943D01*
Y-52997D01*
Y-53052D01*
Y-53106D01*
Y-53160D01*
Y-53214D01*
Y-53268D01*
Y-53322D01*
Y-53376D01*
Y-53430D01*
Y-53484D01*
Y-53538D01*
Y-53592D01*
Y-53646D01*
Y-53700D01*
Y-53754D01*
Y-53808D01*
Y-53863D01*
Y-53917D01*
Y-53971D01*
Y-54025D01*
Y-54079D01*
Y-54133D01*
Y-54187D01*
Y-54241D01*
Y-54295D01*
Y-54349D01*
Y-54403D01*
Y-54457D01*
Y-54511D01*
Y-54565D01*
Y-54619D01*
Y-54673D01*
Y-54728D01*
Y-54782D01*
Y-54836D01*
Y-54890D01*
Y-54944D01*
Y-54998D01*
Y-55052D01*
Y-55106D01*
Y-55160D01*
Y-55214D01*
Y-55268D01*
Y-55322D01*
Y-55376D01*
Y-55430D01*
Y-55484D01*
Y-55538D01*
Y-55592D01*
Y-55647D01*
Y-55701D01*
Y-55755D01*
Y-55809D01*
Y-55863D01*
Y-55917D01*
Y-55971D01*
Y-56025D01*
Y-56079D01*
Y-56133D01*
Y-56187D01*
Y-56241D01*
Y-56295D01*
Y-56349D01*
Y-56403D01*
Y-56457D01*
Y-56511D01*
Y-56566D01*
Y-56620D01*
Y-56674D01*
Y-56728D01*
Y-56782D01*
Y-56836D01*
Y-56890D01*
Y-56944D01*
Y-56998D01*
Y-57052D01*
Y-57106D01*
Y-57160D01*
Y-57214D01*
X395352D01*
Y-57268D01*
Y-57322D01*
Y-57376D01*
Y-57431D01*
Y-57485D01*
Y-57539D01*
Y-57593D01*
Y-57647D01*
Y-57701D01*
Y-57755D01*
Y-57809D01*
Y-57863D01*
Y-57917D01*
Y-57971D01*
Y-58025D01*
Y-58079D01*
Y-58133D01*
Y-58187D01*
Y-58241D01*
Y-58296D01*
Y-58350D01*
Y-58404D01*
Y-58458D01*
Y-58512D01*
Y-58566D01*
Y-58620D01*
Y-58674D01*
Y-58728D01*
Y-58782D01*
Y-58836D01*
Y-58890D01*
Y-58944D01*
Y-58998D01*
Y-59052D01*
Y-59106D01*
Y-59161D01*
Y-59215D01*
Y-59269D01*
Y-59323D01*
Y-59377D01*
Y-59431D01*
Y-59485D01*
Y-59539D01*
Y-59593D01*
Y-59647D01*
Y-59701D01*
Y-59755D01*
Y-59809D01*
Y-59863D01*
Y-59917D01*
Y-59971D01*
Y-60026D01*
Y-60080D01*
Y-60134D01*
Y-60188D01*
Y-60242D01*
Y-60296D01*
Y-60350D01*
Y-60404D01*
Y-60458D01*
Y-60512D01*
Y-60566D01*
Y-60620D01*
Y-60674D01*
Y-60728D01*
Y-60782D01*
Y-60836D01*
Y-60891D01*
Y-60945D01*
Y-60999D01*
Y-61053D01*
Y-61107D01*
Y-61161D01*
Y-61215D01*
Y-61269D01*
Y-61323D01*
Y-61377D01*
Y-61431D01*
Y-61485D01*
Y-61539D01*
Y-61593D01*
Y-61647D01*
Y-61702D01*
Y-61756D01*
Y-61810D01*
Y-61864D01*
Y-61918D01*
Y-61972D01*
Y-62026D01*
Y-62080D01*
X387297D01*
Y-62026D01*
Y-61972D01*
Y-61918D01*
Y-61864D01*
Y-61810D01*
Y-61756D01*
Y-61702D01*
Y-61647D01*
Y-61593D01*
Y-61539D01*
Y-61485D01*
Y-61431D01*
Y-61377D01*
Y-61323D01*
Y-61269D01*
Y-61215D01*
Y-61161D01*
Y-61107D01*
Y-61053D01*
Y-60999D01*
Y-60945D01*
Y-60891D01*
Y-60836D01*
Y-60782D01*
Y-60728D01*
Y-60674D01*
Y-60620D01*
Y-60566D01*
Y-60512D01*
Y-60458D01*
Y-60404D01*
Y-60350D01*
Y-60296D01*
Y-60242D01*
Y-60188D01*
Y-60134D01*
Y-60080D01*
Y-60026D01*
Y-59971D01*
Y-59917D01*
Y-59863D01*
Y-59809D01*
Y-59755D01*
Y-59701D01*
Y-59647D01*
Y-59593D01*
Y-59539D01*
Y-59485D01*
Y-59431D01*
Y-59377D01*
Y-59323D01*
Y-59269D01*
Y-59215D01*
Y-59161D01*
Y-59106D01*
Y-59052D01*
Y-58998D01*
Y-58944D01*
Y-58890D01*
Y-58836D01*
Y-58782D01*
Y-58728D01*
Y-58674D01*
Y-58620D01*
Y-58566D01*
Y-58512D01*
Y-58458D01*
Y-58404D01*
Y-58350D01*
Y-58296D01*
Y-58241D01*
Y-58187D01*
Y-58133D01*
Y-58079D01*
Y-58025D01*
Y-57971D01*
Y-57917D01*
Y-57863D01*
Y-57809D01*
Y-57755D01*
Y-57701D01*
Y-57647D01*
Y-57593D01*
Y-57539D01*
Y-57485D01*
Y-57431D01*
Y-57376D01*
X387242D01*
Y-57322D01*
Y-57268D01*
X387188D01*
Y-57214D01*
X387134D01*
Y-57160D01*
X387080D01*
Y-57106D01*
X386972D01*
Y-57052D01*
X378592D01*
Y-57106D01*
X378484D01*
Y-57160D01*
X378376D01*
Y-57214D01*
X378322D01*
Y-57268D01*
Y-57322D01*
X378268D01*
Y-57376D01*
Y-57431D01*
Y-57485D01*
Y-57539D01*
Y-57593D01*
Y-57647D01*
X378214D01*
Y-57701D01*
X378268D01*
Y-57755D01*
X378214D01*
Y-57809D01*
Y-57863D01*
X378268D01*
Y-57917D01*
Y-57971D01*
Y-58025D01*
Y-58079D01*
Y-58133D01*
Y-58187D01*
Y-58241D01*
Y-58296D01*
Y-58350D01*
Y-58404D01*
Y-58458D01*
Y-58512D01*
Y-58566D01*
Y-58620D01*
Y-58674D01*
Y-58728D01*
Y-58782D01*
Y-58836D01*
Y-58890D01*
Y-58944D01*
Y-58998D01*
Y-59052D01*
Y-59106D01*
Y-59161D01*
Y-59215D01*
Y-59269D01*
Y-59323D01*
Y-59377D01*
Y-59431D01*
Y-59485D01*
Y-59539D01*
Y-59593D01*
Y-59647D01*
Y-59701D01*
Y-59755D01*
Y-59809D01*
Y-59863D01*
Y-59917D01*
Y-59971D01*
Y-60026D01*
Y-60080D01*
Y-60134D01*
Y-60188D01*
Y-60242D01*
Y-60296D01*
Y-60350D01*
Y-60404D01*
Y-60458D01*
Y-60512D01*
Y-60566D01*
Y-60620D01*
X378214D01*
Y-60674D01*
Y-60728D01*
Y-60782D01*
X378160D01*
Y-60836D01*
X378106D01*
Y-60891D01*
X378052D01*
Y-60945D01*
X377998D01*
Y-60999D01*
X377836D01*
Y-61053D01*
X374592D01*
Y-60999D01*
X374430D01*
Y-60945D01*
X374376D01*
Y-60891D01*
X374322D01*
Y-60836D01*
X374268D01*
Y-60782D01*
X374214D01*
Y-60728D01*
Y-60674D01*
Y-60620D01*
Y-60566D01*
X374159D01*
Y-60512D01*
Y-60458D01*
Y-60404D01*
Y-60350D01*
Y-60296D01*
Y-60242D01*
Y-60188D01*
Y-60134D01*
Y-60080D01*
Y-60026D01*
Y-59971D01*
Y-59917D01*
Y-59863D01*
Y-59809D01*
Y-59755D01*
Y-59701D01*
Y-59647D01*
Y-59593D01*
Y-59539D01*
Y-59485D01*
Y-59431D01*
Y-59377D01*
Y-59323D01*
Y-59269D01*
Y-59215D01*
Y-59161D01*
Y-59106D01*
Y-59052D01*
Y-58998D01*
Y-58944D01*
Y-58890D01*
Y-58836D01*
Y-58782D01*
Y-58728D01*
Y-58674D01*
Y-58620D01*
Y-58566D01*
Y-58512D01*
Y-58458D01*
Y-58404D01*
Y-58350D01*
Y-58296D01*
Y-58241D01*
X374214D01*
Y-58187D01*
X374159D01*
Y-58133D01*
Y-58079D01*
X374214D01*
Y-58025D01*
X374159D01*
Y-57971D01*
Y-57917D01*
Y-57863D01*
Y-57809D01*
Y-57755D01*
Y-57701D01*
X374105D01*
Y-57647D01*
Y-57593D01*
X374051D01*
Y-57539D01*
Y-57485D01*
X373997D01*
Y-57431D01*
X373943D01*
Y-57376D01*
X373889D01*
Y-57322D01*
X373835D01*
Y-57268D01*
X373781D01*
Y-57214D01*
X373673D01*
Y-57160D01*
X373565D01*
Y-57106D01*
X373403D01*
Y-57052D01*
X372970D01*
Y-57106D01*
X372808D01*
Y-57160D01*
X372700D01*
Y-57214D01*
X372592D01*
Y-57268D01*
X372538D01*
Y-57322D01*
X372483D01*
Y-57376D01*
X372429D01*
Y-57431D01*
X372375D01*
Y-57485D01*
Y-57539D01*
X372321D01*
Y-57593D01*
Y-57647D01*
X372267D01*
Y-57701D01*
Y-57755D01*
X372213D01*
Y-57809D01*
Y-57863D01*
Y-57917D01*
Y-57971D01*
Y-58025D01*
Y-58079D01*
Y-58133D01*
Y-58187D01*
Y-58241D01*
X372159D01*
Y-58296D01*
X372213D01*
Y-58350D01*
Y-58404D01*
Y-58458D01*
Y-58512D01*
Y-58566D01*
Y-58620D01*
Y-58674D01*
Y-58728D01*
Y-58782D01*
Y-58836D01*
Y-58890D01*
Y-58944D01*
Y-58998D01*
Y-59052D01*
Y-59106D01*
Y-59161D01*
Y-59215D01*
Y-59269D01*
Y-59323D01*
Y-59377D01*
Y-59431D01*
Y-59485D01*
Y-59539D01*
Y-59593D01*
Y-59647D01*
Y-59701D01*
Y-59755D01*
Y-59809D01*
Y-59863D01*
Y-59917D01*
Y-59971D01*
Y-60026D01*
Y-60080D01*
Y-60134D01*
Y-60188D01*
Y-60242D01*
Y-60296D01*
Y-60350D01*
Y-60404D01*
Y-60458D01*
Y-60512D01*
Y-60566D01*
Y-60620D01*
Y-60674D01*
Y-60728D01*
Y-60782D01*
Y-60836D01*
Y-60891D01*
Y-60945D01*
Y-60999D01*
Y-61053D01*
Y-61107D01*
Y-61161D01*
Y-61215D01*
Y-61269D01*
Y-61323D01*
Y-61377D01*
Y-61431D01*
Y-61485D01*
Y-61539D01*
Y-61593D01*
Y-61647D01*
Y-61702D01*
Y-61756D01*
Y-61810D01*
Y-61864D01*
Y-61918D01*
Y-61972D01*
Y-62026D01*
Y-62080D01*
Y-62134D01*
Y-62188D01*
Y-62242D01*
Y-62296D01*
Y-62350D01*
Y-62404D01*
Y-62458D01*
Y-62512D01*
Y-62566D01*
Y-62621D01*
Y-62675D01*
X372159D01*
Y-62729D01*
Y-62783D01*
Y-62837D01*
X372105D01*
Y-62891D01*
Y-62945D01*
X372051D01*
Y-62999D01*
X371943D01*
Y-63053D01*
X371835D01*
Y-63107D01*
X366537D01*
Y-63053D01*
X366374D01*
Y-62999D01*
X366320D01*
Y-62945D01*
X366266D01*
Y-62891D01*
X366212D01*
Y-62837D01*
X366158D01*
Y-62783D01*
Y-62729D01*
Y-62675D01*
Y-62621D01*
Y-62566D01*
Y-62512D01*
Y-62458D01*
Y-62404D01*
Y-62350D01*
Y-62296D01*
Y-62242D01*
Y-62188D01*
Y-62134D01*
Y-62080D01*
Y-62026D01*
Y-61972D01*
Y-61918D01*
Y-61864D01*
Y-61810D01*
Y-61756D01*
Y-61702D01*
Y-61647D01*
Y-61593D01*
Y-61539D01*
Y-61485D01*
Y-61431D01*
Y-61377D01*
Y-61323D01*
Y-61269D01*
Y-61215D01*
Y-61161D01*
Y-61107D01*
Y-61053D01*
Y-60999D01*
Y-60945D01*
Y-60891D01*
Y-60836D01*
Y-60782D01*
Y-60728D01*
Y-60674D01*
Y-60620D01*
Y-60566D01*
Y-60512D01*
Y-60458D01*
Y-60404D01*
Y-60350D01*
Y-60296D01*
Y-60242D01*
Y-60188D01*
Y-60134D01*
Y-60080D01*
Y-60026D01*
Y-59971D01*
Y-59917D01*
Y-59863D01*
Y-59809D01*
Y-59755D01*
Y-59701D01*
Y-59647D01*
Y-59593D01*
Y-59539D01*
X366104D01*
Y-59485D01*
Y-59431D01*
Y-59377D01*
Y-59323D01*
X366050D01*
Y-59269D01*
X365996D01*
Y-59215D01*
X365942D01*
Y-59161D01*
X365888D01*
Y-59106D01*
X365726D01*
Y-59052D01*
X365564D01*
Y-59106D01*
X365401D01*
Y-59161D01*
X365293D01*
Y-59215D01*
X365239D01*
Y-59269D01*
Y-59323D01*
X365185D01*
Y-59377D01*
Y-59431D01*
Y-59485D01*
X365131D01*
Y-59539D01*
Y-59593D01*
Y-59647D01*
Y-59701D01*
Y-59755D01*
Y-59809D01*
Y-59863D01*
Y-59917D01*
Y-59971D01*
Y-60026D01*
Y-60080D01*
Y-60134D01*
Y-60188D01*
Y-60242D01*
Y-60296D01*
Y-60350D01*
Y-60404D01*
Y-60458D01*
Y-60512D01*
Y-60566D01*
Y-60620D01*
Y-60674D01*
Y-60728D01*
Y-60782D01*
Y-60836D01*
Y-60891D01*
Y-60945D01*
Y-60999D01*
Y-61053D01*
Y-61107D01*
Y-61161D01*
Y-61215D01*
Y-61269D01*
Y-61323D01*
Y-61377D01*
Y-61431D01*
Y-61485D01*
Y-61539D01*
Y-61593D01*
Y-61647D01*
Y-61702D01*
Y-61756D01*
Y-61810D01*
Y-61864D01*
Y-61918D01*
Y-61972D01*
Y-62026D01*
Y-62080D01*
Y-62134D01*
Y-62188D01*
Y-62242D01*
Y-62296D01*
Y-62350D01*
Y-62404D01*
Y-62458D01*
Y-62512D01*
Y-62566D01*
Y-62621D01*
Y-62675D01*
Y-62729D01*
Y-62783D01*
X365077D01*
Y-62837D01*
Y-62891D01*
X365023D01*
Y-62945D01*
X364969D01*
Y-62999D01*
X364915D01*
Y-63053D01*
X364753D01*
Y-63107D01*
X354427D01*
Y-63053D01*
X354319D01*
Y-62999D01*
X354211D01*
Y-62945D01*
X354156D01*
Y-62891D01*
Y-62837D01*
X354102D01*
Y-62783D01*
Y-62729D01*
X354048D01*
Y-62675D01*
Y-62621D01*
Y-62566D01*
Y-62512D01*
Y-62458D01*
Y-62404D01*
Y-62350D01*
Y-62296D01*
Y-62242D01*
Y-62188D01*
Y-62134D01*
Y-62080D01*
Y-62026D01*
Y-61972D01*
Y-61918D01*
Y-61864D01*
Y-61810D01*
Y-61756D01*
Y-61702D01*
Y-61647D01*
Y-61593D01*
Y-61539D01*
Y-61485D01*
Y-61431D01*
Y-61377D01*
Y-61323D01*
Y-61269D01*
Y-61215D01*
Y-61161D01*
Y-61107D01*
Y-61053D01*
Y-60999D01*
Y-60945D01*
Y-60891D01*
Y-60836D01*
Y-60782D01*
Y-60728D01*
Y-60674D01*
Y-60620D01*
Y-60566D01*
Y-60512D01*
Y-60458D01*
Y-60404D01*
Y-60350D01*
Y-60296D01*
Y-60242D01*
Y-60188D01*
Y-60134D01*
Y-60080D01*
Y-60026D01*
Y-59971D01*
Y-59917D01*
Y-59863D01*
Y-59809D01*
Y-59755D01*
Y-59701D01*
Y-59647D01*
Y-59593D01*
Y-59539D01*
Y-59485D01*
Y-59431D01*
Y-59377D01*
Y-59323D01*
Y-59269D01*
Y-59215D01*
Y-59161D01*
Y-59106D01*
Y-59052D01*
Y-58998D01*
Y-58944D01*
Y-58890D01*
Y-58836D01*
Y-58782D01*
Y-58728D01*
Y-58674D01*
Y-58620D01*
Y-58566D01*
Y-58512D01*
Y-58458D01*
Y-58404D01*
Y-58350D01*
Y-58296D01*
Y-58241D01*
Y-58187D01*
Y-58133D01*
Y-58079D01*
Y-58025D01*
Y-57971D01*
Y-57917D01*
Y-57863D01*
Y-57809D01*
Y-57755D01*
Y-57701D01*
Y-57647D01*
Y-57593D01*
Y-57539D01*
Y-57485D01*
Y-57431D01*
Y-57376D01*
X353994D01*
Y-57322D01*
Y-57268D01*
X353940D01*
Y-57214D01*
X353886D01*
Y-57160D01*
X353832D01*
Y-57106D01*
X353724D01*
Y-57052D01*
X314799D01*
Y-56998D01*
X314583D01*
Y-56944D01*
X314421D01*
Y-56890D01*
X314313D01*
Y-56836D01*
X314205D01*
Y-56782D01*
X314096D01*
Y-56728D01*
X313988D01*
Y-56674D01*
X313934D01*
Y-56620D01*
X313826D01*
Y-56566D01*
X313772D01*
Y-56511D01*
X313718D01*
Y-56457D01*
X313610D01*
Y-56403D01*
X313556D01*
Y-56349D01*
X313502D01*
Y-56295D01*
X313448D01*
Y-56241D01*
X313394D01*
Y-56187D01*
X313340D01*
Y-56133D01*
X313286D01*
Y-56079D01*
X313232D01*
Y-56025D01*
X313177D01*
Y-55971D01*
X313123D01*
Y-55917D01*
X313069D01*
Y-55863D01*
Y-55809D01*
X313015D01*
Y-55755D01*
X312961D01*
Y-55701D01*
X312907D01*
Y-55647D01*
Y-55592D01*
X312853D01*
Y-55538D01*
X312799D01*
Y-55484D01*
Y-55430D01*
X312745D01*
Y-55376D01*
X312691D01*
Y-55322D01*
Y-55268D01*
X312637D01*
Y-55214D01*
Y-55160D01*
X312583D01*
Y-55106D01*
Y-55052D01*
X312529D01*
Y-54998D01*
Y-54944D01*
Y-54890D01*
X312475D01*
Y-54836D01*
Y-54782D01*
Y-54728D01*
X312421D01*
Y-54673D01*
Y-54619D01*
Y-54565D01*
X312367D01*
Y-54511D01*
Y-54457D01*
Y-54403D01*
X312313D01*
Y-54349D01*
Y-54295D01*
Y-54241D01*
Y-54187D01*
Y-54133D01*
X312258D01*
Y-54079D01*
Y-54025D01*
Y-53971D01*
Y-53917D01*
Y-53863D01*
Y-53808D01*
Y-53754D01*
Y-53700D01*
Y-53646D01*
Y-53592D01*
X312204D01*
Y-53538D01*
Y-53484D01*
X312258D01*
Y-53430D01*
Y-53376D01*
Y-53322D01*
Y-53268D01*
Y-53214D01*
Y-53160D01*
Y-53106D01*
Y-53052D01*
Y-52997D01*
X312313D01*
Y-52943D01*
Y-52889D01*
Y-52835D01*
Y-52781D01*
Y-52727D01*
Y-52673D01*
X312367D01*
Y-52619D01*
Y-52565D01*
Y-52511D01*
X312421D01*
Y-52457D01*
Y-52403D01*
Y-52349D01*
X312475D01*
Y-52295D01*
Y-52241D01*
Y-52187D01*
X312529D01*
Y-52132D01*
Y-52078D01*
X312583D01*
Y-52024D01*
Y-51970D01*
X312637D01*
Y-51916D01*
Y-51862D01*
X312691D01*
Y-51808D01*
Y-51754D01*
X312745D01*
Y-51700D01*
X312799D01*
Y-51646D01*
Y-51592D01*
X312853D01*
Y-51538D01*
X312907D01*
Y-51484D01*
Y-51430D01*
X312961D01*
Y-51376D01*
X313015D01*
Y-51322D01*
X313069D01*
Y-51267D01*
X313123D01*
Y-51213D01*
Y-51159D01*
X313177D01*
Y-51105D01*
X313232D01*
Y-51051D01*
X313286D01*
Y-50997D01*
X313340D01*
Y-50943D01*
X313394D01*
Y-50889D01*
X313502D01*
Y-50835D01*
X313556D01*
Y-50781D01*
X313610D01*
Y-50727D01*
X313664D01*
Y-50673D01*
X313772D01*
Y-50619D01*
X313826D01*
Y-50565D01*
X313934D01*
Y-50511D01*
X314042D01*
Y-50457D01*
X314096D01*
Y-50402D01*
X314205D01*
Y-50348D01*
X314313D01*
Y-50294D01*
X314475D01*
Y-50240D01*
X314637D01*
Y-50186D01*
X314799D01*
Y-50132D01*
X314962D01*
Y-50078D01*
X315232D01*
Y-50024D01*
X326423D01*
Y-49970D01*
X326909D01*
Y-49916D01*
X327180D01*
Y-49862D01*
X327396D01*
Y-49808D01*
X327504D01*
Y-49754D01*
X327666D01*
Y-49700D01*
X327774D01*
Y-49646D01*
X327882D01*
Y-49592D01*
X327991D01*
Y-49538D01*
X328099D01*
Y-49483D01*
X328207D01*
Y-49429D01*
X328261D01*
Y-49375D01*
X328369D01*
Y-49321D01*
X328423D01*
Y-49267D01*
X328477D01*
Y-49213D01*
X328585D01*
Y-49159D01*
X328639D01*
Y-49105D01*
X328693D01*
Y-49051D01*
X328747D01*
Y-48997D01*
X328801D01*
Y-48943D01*
X328855D01*
Y-48889D01*
X328909D01*
Y-48835D01*
X328964D01*
Y-48781D01*
X329018D01*
Y-48727D01*
X329072D01*
Y-48673D01*
Y-48619D01*
X329126D01*
Y-48564D01*
X329180D01*
Y-48510D01*
X329234D01*
Y-48456D01*
Y-48402D01*
X329288D01*
Y-48348D01*
X329342D01*
Y-48294D01*
Y-48240D01*
X329396D01*
Y-48186D01*
Y-48132D01*
X329450D01*
Y-48078D01*
Y-48024D01*
X329504D01*
Y-47970D01*
Y-47916D01*
X329558D01*
Y-47862D01*
Y-47807D01*
X329612D01*
Y-47754D01*
Y-47699D01*
Y-47645D01*
X329666D01*
Y-47591D01*
Y-47537D01*
Y-47483D01*
X329720D01*
Y-47429D01*
Y-47375D01*
Y-47321D01*
X329774D01*
Y-47267D01*
Y-47213D01*
Y-47159D01*
Y-47105D01*
Y-47051D01*
X329829D01*
Y-46997D01*
Y-46942D01*
Y-46889D01*
Y-46834D01*
Y-46780D01*
Y-46726D01*
Y-46672D01*
Y-46618D01*
Y-46564D01*
Y-46510D01*
Y-46456D01*
Y-46402D01*
Y-46348D01*
Y-46294D01*
Y-46240D01*
Y-46186D01*
Y-46132D01*
Y-46077D01*
Y-46023D01*
Y-45969D01*
Y-45915D01*
X329774D01*
Y-45861D01*
Y-45807D01*
Y-45753D01*
Y-45699D01*
Y-45645D01*
X329720D01*
Y-45591D01*
Y-45537D01*
Y-45483D01*
X329666D01*
Y-45429D01*
Y-45375D01*
Y-45321D01*
X329612D01*
Y-45267D01*
Y-45213D01*
Y-45158D01*
X329558D01*
Y-45104D01*
Y-45050D01*
X329504D01*
Y-44996D01*
Y-44942D01*
X329450D01*
Y-44888D01*
Y-44834D01*
X329396D01*
Y-44780D01*
Y-44726D01*
X329342D01*
Y-44672D01*
X329288D01*
Y-44618D01*
Y-44564D01*
X329234D01*
Y-44510D01*
X329180D01*
Y-44456D01*
Y-44402D01*
X329126D01*
Y-44348D01*
X329072D01*
Y-44293D01*
X329018D01*
Y-44239D01*
X328964D01*
Y-44185D01*
Y-44131D01*
X328909D01*
Y-44077D01*
X328855D01*
Y-44023D01*
X328801D01*
Y-43969D01*
X328747D01*
Y-43915D01*
X328693D01*
Y-43861D01*
X328585D01*
Y-43807D01*
X328531D01*
Y-43753D01*
X328477D01*
Y-43699D01*
X328423D01*
Y-43645D01*
X328315D01*
Y-43591D01*
X328261D01*
Y-43537D01*
X328153D01*
Y-43483D01*
X328045D01*
Y-43429D01*
X327991D01*
Y-43374D01*
X327882D01*
Y-43320D01*
X327774D01*
Y-43266D01*
X327612D01*
Y-43212D01*
X327504D01*
Y-43158D01*
X327342D01*
Y-43104D01*
X327126D01*
Y-43050D01*
X326855D01*
Y-42996D01*
X326315D01*
Y-42942D01*
X326260D01*
Y-42996D01*
X310042D01*
Y-42942D01*
X309988D01*
Y-42996D01*
X309880D01*
Y-42942D01*
X309501D01*
Y-42888D01*
X309231D01*
Y-42834D01*
X309069D01*
Y-42780D01*
X308907D01*
Y-42726D01*
X308744D01*
Y-42672D01*
X308636D01*
Y-42618D01*
X308528D01*
Y-42564D01*
X308420D01*
Y-42509D01*
X308312D01*
Y-42455D01*
X308258D01*
Y-42401D01*
X308150D01*
Y-42347D01*
X308096D01*
Y-42293D01*
X307987D01*
Y-42239D01*
X307933D01*
Y-42185D01*
X307879D01*
Y-42131D01*
X307771D01*
Y-42077D01*
X307717D01*
Y-42023D01*
X307663D01*
Y-41969D01*
X307609D01*
Y-41915D01*
X307555D01*
Y-41861D01*
X307501D01*
Y-41807D01*
X307447D01*
Y-41753D01*
X307393D01*
Y-41699D01*
Y-41644D01*
X307339D01*
Y-41590D01*
X307285D01*
Y-41536D01*
X307231D01*
Y-41482D01*
X307177D01*
Y-41428D01*
Y-41374D01*
X307122D01*
Y-41320D01*
X307068D01*
Y-41266D01*
Y-41212D01*
X307014D01*
Y-41158D01*
Y-41104D01*
X306960D01*
Y-41050D01*
Y-40996D01*
X306906D01*
Y-40942D01*
Y-40888D01*
X306852D01*
Y-40834D01*
Y-40780D01*
X306798D01*
Y-40725D01*
Y-40671D01*
Y-40617D01*
X306744D01*
Y-40563D01*
Y-40509D01*
Y-40455D01*
X306690D01*
Y-40401D01*
Y-40347D01*
Y-40293D01*
X306636D01*
Y-40239D01*
Y-40185D01*
Y-40131D01*
Y-40077D01*
Y-40023D01*
X306582D01*
Y-39968D01*
Y-39915D01*
Y-39860D01*
Y-39806D01*
Y-39752D01*
Y-39698D01*
Y-39644D01*
Y-39590D01*
Y-39536D01*
Y-39482D01*
Y-39428D01*
Y-39374D01*
Y-39320D01*
Y-39266D01*
Y-39212D01*
Y-39158D01*
Y-39103D01*
Y-39050D01*
Y-38995D01*
Y-38941D01*
Y-38887D01*
X306636D01*
Y-38833D01*
Y-38779D01*
Y-38725D01*
Y-38671D01*
Y-38617D01*
X306690D01*
Y-38563D01*
Y-38509D01*
Y-38455D01*
Y-38401D01*
X306744D01*
Y-38347D01*
Y-38293D01*
Y-38238D01*
X306798D01*
Y-38184D01*
Y-38130D01*
X306852D01*
Y-38076D01*
Y-38022D01*
Y-37968D01*
X306906D01*
Y-37914D01*
Y-37860D01*
X306960D01*
Y-37806D01*
Y-37752D01*
X307014D01*
Y-37698D01*
X307068D01*
Y-37644D01*
Y-37590D01*
X307122D01*
Y-37536D01*
Y-37482D01*
X307177D01*
Y-37428D01*
X307231D01*
Y-37374D01*
X307285D01*
Y-37319D01*
Y-37265D01*
X307339D01*
Y-37211D01*
X307393D01*
Y-37157D01*
X307447D01*
Y-37103D01*
X307501D01*
Y-37049D01*
X307555D01*
Y-36995D01*
X307609D01*
Y-36941D01*
X307663D01*
Y-36887D01*
X307717D01*
Y-36833D01*
X307771D01*
Y-36779D01*
X307825D01*
Y-36725D01*
X307879D01*
Y-36671D01*
X307987D01*
Y-36617D01*
X308042D01*
Y-36563D01*
X308096D01*
Y-36509D01*
X308204D01*
Y-36454D01*
X308258D01*
Y-36400D01*
X308366D01*
Y-36346D01*
X308474D01*
Y-36292D01*
X308582D01*
Y-36238D01*
X308690D01*
Y-36184D01*
X308853D01*
Y-36130D01*
X309015D01*
Y-36076D01*
X309177D01*
Y-36022D01*
X309393D01*
Y-35968D01*
X309664D01*
Y-35914D01*
X320043D01*
Y-35860D01*
X320422D01*
Y-35806D01*
X320638D01*
Y-35752D01*
X320800D01*
Y-35698D01*
X320962D01*
Y-35644D01*
X321071D01*
Y-35590D01*
X321233D01*
Y-35535D01*
X321341D01*
Y-35481D01*
X321395D01*
Y-35427D01*
X321503D01*
Y-35373D01*
X321611D01*
Y-35319D01*
X321665D01*
Y-35265D01*
X321773D01*
Y-35211D01*
X321827D01*
Y-35157D01*
X321882D01*
Y-35103D01*
X321990D01*
Y-35049D01*
X322044D01*
Y-34995D01*
X322098D01*
Y-34941D01*
X322152D01*
Y-34887D01*
X322206D01*
Y-34833D01*
X322260D01*
Y-34779D01*
X322314D01*
Y-34725D01*
X322368D01*
Y-34670D01*
X322422D01*
Y-34616D01*
X322476D01*
Y-34562D01*
Y-34508D01*
X322530D01*
Y-34454D01*
X322584D01*
Y-34400D01*
X322638D01*
Y-34346D01*
Y-34292D01*
X322692D01*
Y-34238D01*
X322746D01*
Y-34184D01*
Y-34130D01*
X322800D01*
Y-34076D01*
Y-34022D01*
X322855D01*
Y-33968D01*
Y-33914D01*
X322909D01*
Y-33860D01*
Y-33806D01*
X322963D01*
Y-33751D01*
Y-33697D01*
X323017D01*
Y-33643D01*
Y-33589D01*
Y-33535D01*
X323071D01*
Y-33481D01*
Y-33427D01*
Y-33373D01*
X323125D01*
Y-33319D01*
Y-33265D01*
Y-33211D01*
Y-33157D01*
X323179D01*
Y-33103D01*
Y-33049D01*
Y-32994D01*
Y-32941D01*
Y-32886D01*
Y-32832D01*
X323233D01*
Y-32778D01*
Y-32724D01*
Y-32670D01*
Y-32616D01*
Y-32562D01*
Y-32508D01*
Y-32454D01*
Y-32400D01*
Y-32346D01*
Y-32292D01*
Y-32238D01*
Y-32184D01*
Y-32129D01*
Y-32076D01*
Y-32021D01*
Y-31967D01*
X323179D01*
Y-31913D01*
Y-31859D01*
Y-31805D01*
Y-31751D01*
Y-31697D01*
Y-31643D01*
X323125D01*
Y-31589D01*
Y-31535D01*
Y-31481D01*
Y-31427D01*
X323071D01*
Y-31373D01*
Y-31319D01*
Y-31265D01*
X323017D01*
Y-31211D01*
Y-31156D01*
Y-31102D01*
X322963D01*
Y-31048D01*
Y-30994D01*
X322909D01*
Y-30940D01*
Y-30886D01*
X322855D01*
Y-30832D01*
Y-30778D01*
X322800D01*
Y-30724D01*
Y-30670D01*
X322746D01*
Y-30616D01*
Y-30562D01*
X322692D01*
Y-30508D01*
X322638D01*
Y-30454D01*
Y-30400D01*
X322584D01*
Y-30345D01*
X322530D01*
Y-30291D01*
Y-30237D01*
X322476D01*
Y-30183D01*
X322422D01*
Y-30129D01*
X322368D01*
Y-30075D01*
X322314D01*
Y-30021D01*
X322260D01*
Y-29967D01*
X322206D01*
Y-29913D01*
X322152D01*
Y-29859D01*
X322098D01*
Y-29805D01*
X322044D01*
Y-29751D01*
X321990D01*
Y-29697D01*
X321936D01*
Y-29643D01*
X321827D01*
Y-29589D01*
X321773D01*
Y-29535D01*
X321719D01*
Y-29480D01*
X321611D01*
Y-29426D01*
X321557D01*
Y-29372D01*
X321449D01*
Y-29318D01*
X321341D01*
Y-29264D01*
X321233D01*
Y-29210D01*
X321125D01*
Y-29156D01*
X320962D01*
Y-29102D01*
X320854D01*
Y-29048D01*
X320638D01*
Y-28994D01*
X320422D01*
Y-28940D01*
X320097D01*
Y-28886D01*
X292039D01*
Y-28832D01*
X291715D01*
Y-28778D01*
X291499D01*
Y-28724D01*
X291336D01*
Y-28670D01*
X291174D01*
Y-28615D01*
X291066D01*
Y-28561D01*
X290958D01*
Y-28507D01*
X290796D01*
Y-28453D01*
X290742D01*
Y-28399D01*
X290634D01*
Y-28345D01*
X290526D01*
Y-28291D01*
X290471D01*
Y-28237D01*
X290363D01*
Y-28183D01*
X290309D01*
Y-28129D01*
X290255D01*
Y-28075D01*
X290147D01*
Y-28021D01*
X290093D01*
Y-27967D01*
X290039D01*
Y-27913D01*
X289985D01*
Y-27859D01*
X289931D01*
Y-27805D01*
X289877D01*
Y-27751D01*
X289823D01*
Y-27696D01*
X289769D01*
Y-27642D01*
X289715D01*
Y-27588D01*
Y-27534D01*
X289661D01*
Y-27480D01*
X289606D01*
Y-27426D01*
X289552D01*
Y-27372D01*
X289498D01*
Y-27318D01*
Y-27264D01*
X289444D01*
Y-27210D01*
X289390D01*
Y-27156D01*
Y-27102D01*
X289336D01*
Y-27048D01*
Y-26994D01*
X289282D01*
Y-26940D01*
Y-26886D01*
X289228D01*
Y-26831D01*
Y-26777D01*
X289174D01*
Y-26723D01*
Y-26669D01*
X289120D01*
Y-26615D01*
Y-26561D01*
Y-26507D01*
X289066D01*
Y-26453D01*
Y-26399D01*
Y-26345D01*
X289012D01*
Y-26291D01*
Y-26237D01*
Y-26183D01*
Y-26129D01*
X288958D01*
Y-26075D01*
Y-26021D01*
Y-25967D01*
Y-25912D01*
Y-25858D01*
X288904D01*
Y-25804D01*
Y-25750D01*
Y-25696D01*
Y-25642D01*
Y-25588D01*
Y-25534D01*
Y-25480D01*
Y-25426D01*
Y-25372D01*
Y-25318D01*
Y-25264D01*
Y-25210D01*
Y-25155D01*
Y-25102D01*
Y-25047D01*
Y-24993D01*
Y-24939D01*
Y-24885D01*
Y-24831D01*
X288958D01*
Y-24777D01*
Y-24723D01*
Y-24669D01*
Y-24615D01*
Y-24561D01*
X289012D01*
Y-24507D01*
Y-24453D01*
Y-24399D01*
Y-24345D01*
X289066D01*
Y-24291D01*
Y-24237D01*
Y-24182D01*
X289120D01*
Y-24128D01*
Y-24074D01*
X289174D01*
Y-24020D01*
Y-23966D01*
Y-23912D01*
X289228D01*
Y-23858D01*
Y-23804D01*
X289282D01*
Y-23750D01*
Y-23696D01*
X289336D01*
Y-23642D01*
Y-23588D01*
X289390D01*
Y-23534D01*
X289444D01*
Y-23480D01*
Y-23426D01*
X289498D01*
Y-23371D01*
X289552D01*
Y-23317D01*
Y-23263D01*
X289606D01*
Y-23209D01*
X289661D01*
Y-23155D01*
X289715D01*
Y-23101D01*
X289769D01*
Y-23047D01*
Y-22993D01*
X289823D01*
Y-22939D01*
X289877D01*
Y-22885D01*
X289931D01*
Y-22831D01*
X289985D01*
Y-22777D01*
X290039D01*
Y-22723D01*
X290147D01*
Y-22669D01*
X290201D01*
Y-22615D01*
X290255D01*
Y-22561D01*
X290309D01*
Y-22506D01*
X290417D01*
Y-22452D01*
X290471D01*
Y-22398D01*
X290580D01*
Y-22344D01*
X290634D01*
Y-22290D01*
X290742D01*
Y-22236D01*
X290850D01*
Y-22182D01*
X290958D01*
Y-22128D01*
X291066D01*
Y-22074D01*
X291228D01*
Y-22020D01*
X291390D01*
Y-21966D01*
X291553D01*
Y-21912D01*
X291769D01*
Y-21858D01*
X292147D01*
Y-21804D01*
X292201D01*
Y-21858D01*
X292255D01*
Y-21804D01*
X335018D01*
Y-21750D01*
X335289D01*
Y-21696D01*
X335505D01*
Y-21642D01*
X335667D01*
Y-21587D01*
X335829D01*
Y-21533D01*
X335938D01*
Y-21479D01*
X336046D01*
Y-21425D01*
X336154D01*
Y-21371D01*
X336262D01*
Y-21317D01*
X336370D01*
Y-21263D01*
X336424D01*
Y-21209D01*
X336532D01*
Y-21155D01*
X336586D01*
Y-21101D01*
X336695D01*
Y-21047D01*
X336749D01*
Y-20993D01*
X336803D01*
Y-20939D01*
X336857D01*
Y-20885D01*
X336911D01*
Y-20831D01*
X336965D01*
Y-20776D01*
X337019D01*
Y-20722D01*
X337073D01*
Y-20668D01*
X337127D01*
Y-20614D01*
X337181D01*
Y-20560D01*
X337235D01*
Y-20506D01*
X337289D01*
Y-20452D01*
X337343D01*
Y-20398D01*
Y-20344D01*
X337397D01*
Y-20290D01*
X337451D01*
Y-20236D01*
Y-20182D01*
X337505D01*
Y-20128D01*
X337560D01*
Y-20074D01*
Y-20020D01*
X337614D01*
Y-19966D01*
Y-19911D01*
X337668D01*
Y-19858D01*
Y-19803D01*
X337722D01*
Y-19749D01*
Y-19695D01*
X337776D01*
Y-19641D01*
Y-19587D01*
X337830D01*
Y-19533D01*
Y-19479D01*
Y-19425D01*
X337884D01*
Y-19371D01*
Y-19317D01*
Y-19263D01*
X337938D01*
Y-19209D01*
Y-19155D01*
Y-19101D01*
Y-19047D01*
X337992D01*
Y-18993D01*
Y-18938D01*
Y-18884D01*
Y-18830D01*
Y-18776D01*
Y-18722D01*
X338046D01*
Y-18668D01*
Y-18614D01*
Y-18560D01*
Y-18506D01*
Y-18452D01*
Y-18398D01*
Y-18344D01*
Y-18290D01*
Y-18236D01*
Y-18181D01*
Y-18127D01*
Y-18073D01*
Y-18019D01*
Y-17965D01*
Y-17911D01*
Y-17857D01*
X337992D01*
Y-17803D01*
Y-17749D01*
Y-17695D01*
Y-17641D01*
Y-17587D01*
Y-17533D01*
X337938D01*
Y-17479D01*
Y-17425D01*
Y-17371D01*
Y-17317D01*
X337884D01*
Y-17263D01*
Y-17208D01*
Y-17154D01*
X337830D01*
Y-17100D01*
Y-17046D01*
X337776D01*
Y-16992D01*
Y-16938D01*
Y-16884D01*
X337722D01*
Y-16830D01*
Y-16776D01*
X337668D01*
Y-16722D01*
Y-16668D01*
X337614D01*
Y-16614D01*
Y-16560D01*
X337560D01*
Y-16506D01*
X337505D01*
Y-16452D01*
Y-16398D01*
X337451D01*
Y-16343D01*
X337397D01*
Y-16289D01*
Y-16235D01*
X337343D01*
Y-16181D01*
X337289D01*
Y-16127D01*
X337235D01*
Y-16073D01*
Y-16019D01*
X337181D01*
Y-15965D01*
X337127D01*
Y-15911D01*
X337073D01*
Y-15857D01*
X337019D01*
Y-15803D01*
X336965D01*
Y-15749D01*
X336911D01*
Y-15695D01*
X336857D01*
Y-15641D01*
X336749D01*
Y-15587D01*
X336695D01*
Y-15532D01*
X336640D01*
Y-15478D01*
X336586D01*
Y-15424D01*
X336478D01*
Y-15370D01*
X336370D01*
Y-15316D01*
X336316D01*
Y-15262D01*
X336208D01*
Y-15208D01*
X336100D01*
Y-15154D01*
X335992D01*
Y-15100D01*
X335883D01*
Y-15046D01*
X335721D01*
Y-14992D01*
X335613D01*
Y-14938D01*
X335397D01*
Y-14884D01*
X335181D01*
Y-14830D01*
X334748D01*
Y-14776D01*
X326585D01*
Y-14722D01*
X326260D01*
Y-14668D01*
X326098D01*
Y-14614D01*
X325882D01*
Y-14559D01*
X325774D01*
Y-14505D01*
X325612D01*
Y-14451D01*
X325504D01*
Y-14397D01*
X325395D01*
Y-14343D01*
X325287D01*
Y-14289D01*
X325233D01*
Y-14235D01*
X325125D01*
Y-14181D01*
X325071D01*
Y-14127D01*
X324963D01*
Y-14073D01*
X324909D01*
Y-14019D01*
X324855D01*
Y-13965D01*
X324747D01*
Y-13911D01*
X324693D01*
Y-13857D01*
X324639D01*
Y-13803D01*
X324585D01*
Y-13748D01*
X324531D01*
Y-13694D01*
X324476D01*
Y-13640D01*
X324422D01*
Y-13586D01*
X324368D01*
Y-13532D01*
X324314D01*
Y-13478D01*
Y-13424D01*
X324260D01*
Y-13370D01*
X324206D01*
Y-13316D01*
X324152D01*
Y-13262D01*
Y-13208D01*
X324098D01*
Y-13154D01*
X324044D01*
Y-13100D01*
Y-13046D01*
X323990D01*
Y-12992D01*
X323936D01*
Y-12937D01*
Y-12883D01*
X323882D01*
Y-12829D01*
Y-12775D01*
X323828D01*
Y-12721D01*
Y-12667D01*
X323774D01*
Y-12613D01*
Y-12559D01*
Y-12505D01*
X323720D01*
Y-12451D01*
Y-12397D01*
Y-12343D01*
X323665D01*
Y-12289D01*
Y-12235D01*
Y-12181D01*
X323611D01*
Y-12127D01*
Y-12072D01*
Y-12019D01*
Y-11964D01*
X323557D01*
Y-11910D01*
Y-11856D01*
Y-11802D01*
Y-11748D01*
Y-11694D01*
Y-11640D01*
Y-11586D01*
X323503D01*
Y-11532D01*
X323557D01*
Y-11478D01*
X323503D01*
Y-11424D01*
Y-11370D01*
Y-11316D01*
Y-11262D01*
Y-11208D01*
Y-11153D01*
Y-11099D01*
Y-11045D01*
Y-10991D01*
Y-10937D01*
Y-10883D01*
X323557D01*
Y-10829D01*
Y-10775D01*
Y-10721D01*
Y-10667D01*
Y-10613D01*
Y-10559D01*
X323611D01*
Y-10505D01*
Y-10451D01*
Y-10397D01*
Y-10343D01*
X323665D01*
Y-10289D01*
Y-10234D01*
Y-10180D01*
X323720D01*
Y-10126D01*
Y-10072D01*
Y-10018D01*
X323774D01*
Y-9964D01*
Y-9910D01*
Y-9856D01*
X323828D01*
Y-9802D01*
Y-9748D01*
X323882D01*
Y-9694D01*
Y-9640D01*
X323936D01*
Y-9586D01*
Y-9532D01*
X323990D01*
Y-9478D01*
X324044D01*
Y-9424D01*
Y-9369D01*
X324098D01*
Y-9315D01*
Y-9261D01*
X324152D01*
Y-9207D01*
X324206D01*
Y-9153D01*
X324260D01*
Y-9099D01*
Y-9045D01*
X324314D01*
Y-8991D01*
X324368D01*
Y-8937D01*
X324422D01*
Y-8883D01*
X324476D01*
Y-8829D01*
X324531D01*
Y-8775D01*
X324585D01*
Y-8721D01*
X324639D01*
Y-8667D01*
X324693D01*
Y-8613D01*
X324747D01*
Y-8558D01*
X324801D01*
Y-8504D01*
X324909D01*
Y-8450D01*
X324963D01*
Y-8396D01*
X325017D01*
Y-8342D01*
X325125D01*
Y-8288D01*
X325179D01*
Y-8234D01*
X325287D01*
Y-8180D01*
X325395D01*
Y-8126D01*
X325504D01*
Y-8072D01*
X325612D01*
Y-8018D01*
X325720D01*
Y-7964D01*
X325882D01*
Y-7910D01*
X326044D01*
Y-7856D01*
X326260D01*
Y-7802D01*
X326477D01*
Y-7748D01*
X327071D01*
Y-7694D01*
X395298D01*
Y-7748D01*
D02*
G37*
G36*
X393514Y-30345D02*
X393730D01*
Y-30400D01*
X393838D01*
Y-30454D01*
X394000D01*
Y-30508D01*
X394108D01*
Y-30562D01*
X394162D01*
Y-30616D01*
X394270D01*
Y-30670D01*
X394325D01*
Y-30724D01*
X394379D01*
Y-30778D01*
X394487D01*
Y-30832D01*
X394541D01*
Y-30886D01*
X394595D01*
Y-30940D01*
X394649D01*
Y-30994D01*
Y-31048D01*
X394703D01*
Y-31102D01*
X394757D01*
Y-31156D01*
X394811D01*
Y-31211D01*
Y-31265D01*
X394865D01*
Y-31319D01*
Y-31373D01*
X394919D01*
Y-31427D01*
Y-31481D01*
X394973D01*
Y-31535D01*
Y-31589D01*
X395027D01*
Y-31643D01*
Y-31697D01*
Y-31751D01*
X395081D01*
Y-31805D01*
Y-31859D01*
Y-31913D01*
Y-31967D01*
Y-32021D01*
X395135D01*
Y-32076D01*
Y-32129D01*
Y-32184D01*
Y-32238D01*
Y-32292D01*
Y-32346D01*
Y-32400D01*
Y-32454D01*
Y-32508D01*
Y-32562D01*
X395081D01*
Y-32616D01*
Y-32670D01*
Y-32724D01*
Y-32778D01*
Y-32832D01*
X395027D01*
Y-32886D01*
Y-32941D01*
Y-32994D01*
X394973D01*
Y-33049D01*
Y-33103D01*
Y-33157D01*
X394919D01*
Y-33211D01*
Y-33265D01*
X394865D01*
Y-33319D01*
X394811D01*
Y-33373D01*
Y-33427D01*
X394757D01*
Y-33481D01*
Y-33535D01*
X394703D01*
Y-33589D01*
X394649D01*
Y-33643D01*
X394595D01*
Y-33697D01*
X394541D01*
Y-33751D01*
X394487D01*
Y-33806D01*
X394433D01*
Y-33860D01*
X394379D01*
Y-33914D01*
X394270D01*
Y-33968D01*
X394216D01*
Y-34022D01*
X394108D01*
Y-34076D01*
X394054D01*
Y-34130D01*
X393892D01*
Y-34184D01*
X393784D01*
Y-34238D01*
X393622D01*
Y-34292D01*
X393297D01*
Y-34346D01*
X392919D01*
Y-34292D01*
X392595D01*
Y-34238D01*
X392432D01*
Y-34184D01*
X392270D01*
Y-34130D01*
X392162D01*
Y-34076D01*
X392054D01*
Y-34022D01*
X392000D01*
Y-33968D01*
X391892D01*
Y-33914D01*
X391838D01*
Y-33860D01*
X391784D01*
Y-33806D01*
X391730D01*
Y-33751D01*
X391675D01*
Y-33697D01*
X391621D01*
Y-33643D01*
X391567D01*
Y-33589D01*
X391513D01*
Y-33535D01*
X391459D01*
Y-33481D01*
Y-33427D01*
X391405D01*
Y-33373D01*
X391351D01*
Y-33319D01*
Y-33265D01*
X391297D01*
Y-33211D01*
Y-33157D01*
X391243D01*
Y-33103D01*
Y-33049D01*
X391189D01*
Y-32994D01*
Y-32941D01*
Y-32886D01*
X391135D01*
Y-32832D01*
Y-32778D01*
Y-32724D01*
Y-32670D01*
X391081D01*
Y-32616D01*
Y-32562D01*
Y-32508D01*
Y-32454D01*
Y-32400D01*
Y-32346D01*
Y-32292D01*
Y-32238D01*
Y-32184D01*
Y-32129D01*
Y-32076D01*
Y-32021D01*
Y-31967D01*
X391135D01*
Y-31913D01*
Y-31859D01*
Y-31805D01*
Y-31751D01*
X391189D01*
Y-31697D01*
Y-31643D01*
Y-31589D01*
X391243D01*
Y-31535D01*
Y-31481D01*
Y-31427D01*
X391297D01*
Y-31373D01*
Y-31319D01*
X391351D01*
Y-31265D01*
X391405D01*
Y-31211D01*
Y-31156D01*
X391459D01*
Y-31102D01*
X391513D01*
Y-31048D01*
Y-30994D01*
X391567D01*
Y-30940D01*
X391621D01*
Y-30886D01*
X391675D01*
Y-30832D01*
X391730D01*
Y-30778D01*
X391784D01*
Y-30724D01*
X391892D01*
Y-30670D01*
X391946D01*
Y-30616D01*
X392054D01*
Y-30562D01*
X392108D01*
Y-30508D01*
X392216D01*
Y-30454D01*
X392324D01*
Y-30400D01*
X392487D01*
Y-30345D01*
X392703D01*
Y-30291D01*
X393514D01*
Y-30345D01*
D02*
G37*
G36*
X393406Y-37644D02*
X393676D01*
Y-37698D01*
X393838D01*
Y-37752D01*
X393946D01*
Y-37806D01*
X394054D01*
Y-37860D01*
X394162D01*
Y-37914D01*
X394216D01*
Y-37968D01*
X394325D01*
Y-38022D01*
X394379D01*
Y-38076D01*
X394433D01*
Y-38130D01*
X394487D01*
Y-38184D01*
X394541D01*
Y-38238D01*
X394595D01*
Y-38293D01*
X394649D01*
Y-38347D01*
X394703D01*
Y-38401D01*
X394757D01*
Y-38455D01*
Y-38509D01*
X394811D01*
Y-38563D01*
X394865D01*
Y-38617D01*
Y-38671D01*
X394919D01*
Y-38725D01*
Y-38779D01*
X394973D01*
Y-38833D01*
Y-38887D01*
X395027D01*
Y-38941D01*
Y-38995D01*
Y-39050D01*
Y-39103D01*
X395081D01*
Y-39158D01*
Y-39212D01*
Y-39266D01*
Y-39320D01*
X395135D01*
Y-39374D01*
Y-39428D01*
Y-39482D01*
Y-39536D01*
Y-39590D01*
Y-39644D01*
Y-39698D01*
Y-39752D01*
Y-39806D01*
Y-39860D01*
Y-39915D01*
X395081D01*
Y-39968D01*
Y-40023D01*
Y-40077D01*
Y-40131D01*
X395027D01*
Y-40185D01*
Y-40239D01*
Y-40293D01*
X394973D01*
Y-40347D01*
Y-40401D01*
Y-40455D01*
X394919D01*
Y-40509D01*
Y-40563D01*
X394865D01*
Y-40617D01*
Y-40671D01*
X394811D01*
Y-40725D01*
X394757D01*
Y-40780D01*
Y-40834D01*
X394703D01*
Y-40888D01*
X394649D01*
Y-40942D01*
X394595D01*
Y-40996D01*
X394541D01*
Y-41050D01*
X394487D01*
Y-41104D01*
X394433D01*
Y-41158D01*
X394379D01*
Y-41212D01*
X394325D01*
Y-41266D01*
X394216D01*
Y-41320D01*
X394162D01*
Y-41374D01*
X394054D01*
Y-41428D01*
X393946D01*
Y-41482D01*
X393838D01*
Y-41536D01*
X393676D01*
Y-41590D01*
X393406D01*
Y-41644D01*
X392811D01*
Y-41590D01*
X392541D01*
Y-41536D01*
X392378D01*
Y-41482D01*
X392270D01*
Y-41428D01*
X392162D01*
Y-41374D01*
X392054D01*
Y-41320D01*
X391946D01*
Y-41266D01*
X391892D01*
Y-41212D01*
X391838D01*
Y-41158D01*
X391784D01*
Y-41104D01*
X391675D01*
Y-41050D01*
X391621D01*
Y-40996D01*
X391567D01*
Y-40942D01*
Y-40888D01*
X391513D01*
Y-40834D01*
X391459D01*
Y-40780D01*
X391405D01*
Y-40725D01*
Y-40671D01*
X391351D01*
Y-40617D01*
Y-40563D01*
X391297D01*
Y-40509D01*
Y-40455D01*
X391243D01*
Y-40401D01*
Y-40347D01*
X391189D01*
Y-40293D01*
Y-40239D01*
Y-40185D01*
X391135D01*
Y-40131D01*
Y-40077D01*
Y-40023D01*
Y-39968D01*
X391081D01*
Y-39915D01*
Y-39860D01*
Y-39806D01*
Y-39752D01*
Y-39698D01*
Y-39644D01*
Y-39590D01*
Y-39536D01*
Y-39482D01*
Y-39428D01*
Y-39374D01*
Y-39320D01*
Y-39266D01*
X391135D01*
Y-39212D01*
Y-39158D01*
Y-39103D01*
Y-39050D01*
X391189D01*
Y-38995D01*
Y-38941D01*
Y-38887D01*
X391243D01*
Y-38833D01*
Y-38779D01*
X391297D01*
Y-38725D01*
Y-38671D01*
X391351D01*
Y-38617D01*
Y-38563D01*
X391405D01*
Y-38509D01*
Y-38455D01*
X391459D01*
Y-38401D01*
X391513D01*
Y-38347D01*
X391567D01*
Y-38293D01*
Y-38238D01*
X391621D01*
Y-38184D01*
X391675D01*
Y-38130D01*
X391730D01*
Y-38076D01*
X391838D01*
Y-38022D01*
X391892D01*
Y-37968D01*
X391946D01*
Y-37914D01*
X392054D01*
Y-37860D01*
X392162D01*
Y-37806D01*
X392270D01*
Y-37752D01*
X392378D01*
Y-37698D01*
X392541D01*
Y-37644D01*
X392757D01*
Y-37590D01*
X393406D01*
Y-37644D01*
D02*
G37*
G36*
X299338Y-35968D02*
X299608D01*
Y-36022D01*
X299824D01*
Y-36076D01*
X299986D01*
Y-36130D01*
X300149D01*
Y-36184D01*
X300311D01*
Y-36238D01*
X300419D01*
Y-36292D01*
X300527D01*
Y-36346D01*
X300635D01*
Y-36400D01*
X300689D01*
Y-36454D01*
X300797D01*
Y-36509D01*
X300851D01*
Y-36563D01*
X300959D01*
Y-36617D01*
X301013D01*
Y-36671D01*
X301122D01*
Y-36725D01*
X301176D01*
Y-36779D01*
X301230D01*
Y-36833D01*
X301284D01*
Y-36887D01*
X301338D01*
Y-36941D01*
X301392D01*
Y-36995D01*
X301446D01*
Y-37049D01*
X301500D01*
Y-37103D01*
X301554D01*
Y-37157D01*
X301608D01*
Y-37211D01*
X301662D01*
Y-37265D01*
Y-37319D01*
X301716D01*
Y-37374D01*
X301770D01*
Y-37428D01*
X301824D01*
Y-37482D01*
Y-37536D01*
X301878D01*
Y-37590D01*
X301933D01*
Y-37644D01*
Y-37698D01*
X301987D01*
Y-37752D01*
Y-37806D01*
X302041D01*
Y-37860D01*
Y-37914D01*
X302095D01*
Y-37968D01*
Y-38022D01*
X302149D01*
Y-38076D01*
Y-38130D01*
X302203D01*
Y-38184D01*
Y-38238D01*
Y-38293D01*
X302257D01*
Y-38347D01*
Y-38401D01*
Y-38455D01*
X302311D01*
Y-38509D01*
Y-38563D01*
Y-38617D01*
Y-38671D01*
X302365D01*
Y-38725D01*
Y-38779D01*
Y-38833D01*
Y-38887D01*
Y-38941D01*
X302419D01*
Y-38995D01*
Y-39050D01*
Y-39103D01*
Y-39158D01*
Y-39212D01*
Y-39266D01*
Y-39320D01*
Y-39374D01*
Y-39428D01*
Y-39482D01*
Y-39536D01*
Y-39590D01*
Y-39644D01*
Y-39698D01*
Y-39752D01*
Y-39806D01*
Y-39860D01*
Y-39915D01*
Y-39968D01*
X302365D01*
Y-40023D01*
Y-40077D01*
Y-40131D01*
Y-40185D01*
Y-40239D01*
X302311D01*
Y-40293D01*
Y-40347D01*
Y-40401D01*
Y-40455D01*
X302257D01*
Y-40509D01*
Y-40563D01*
Y-40617D01*
X302203D01*
Y-40671D01*
Y-40725D01*
X302149D01*
Y-40780D01*
Y-40834D01*
Y-40888D01*
X302095D01*
Y-40942D01*
Y-40996D01*
X302041D01*
Y-41050D01*
Y-41104D01*
X301987D01*
Y-41158D01*
X301933D01*
Y-41212D01*
Y-41266D01*
X301878D01*
Y-41320D01*
Y-41374D01*
X301824D01*
Y-41428D01*
X301770D01*
Y-41482D01*
Y-41536D01*
X301716D01*
Y-41590D01*
X301662D01*
Y-41644D01*
X301608D01*
Y-41699D01*
X301554D01*
Y-41753D01*
Y-41807D01*
X301500D01*
Y-41861D01*
X301446D01*
Y-41915D01*
X301392D01*
Y-41969D01*
X301338D01*
Y-42023D01*
X301284D01*
Y-42077D01*
X301176D01*
Y-42131D01*
X301122D01*
Y-42185D01*
X301068D01*
Y-42239D01*
X301013D01*
Y-42293D01*
X300905D01*
Y-42347D01*
X300851D01*
Y-42401D01*
X300743D01*
Y-42455D01*
X300689D01*
Y-42509D01*
X300581D01*
Y-42564D01*
X300473D01*
Y-42618D01*
X300365D01*
Y-42672D01*
X300257D01*
Y-42726D01*
X300095D01*
Y-42780D01*
X299932D01*
Y-42834D01*
X299770D01*
Y-42888D01*
X299500D01*
Y-42942D01*
X299121D01*
Y-42996D01*
X298743D01*
Y-42942D01*
X298689D01*
Y-42996D01*
X298635D01*
Y-42942D01*
X298581D01*
Y-42996D01*
X298527D01*
Y-42942D01*
X298202D01*
Y-42888D01*
X297932D01*
Y-42834D01*
X297716D01*
Y-42780D01*
X297554D01*
Y-42726D01*
X297445D01*
Y-42672D01*
X297283D01*
Y-42618D01*
X297175D01*
Y-42564D01*
X297067D01*
Y-42509D01*
X297013D01*
Y-42455D01*
X296905D01*
Y-42401D01*
X296797D01*
Y-42347D01*
X296743D01*
Y-42293D01*
X296689D01*
Y-42239D01*
X296581D01*
Y-42185D01*
X296526D01*
Y-42131D01*
X296472D01*
Y-42077D01*
X296418D01*
Y-42023D01*
X296364D01*
Y-41969D01*
X296310D01*
Y-41915D01*
X296256D01*
Y-41861D01*
X296202D01*
Y-41807D01*
X296148D01*
Y-41753D01*
X296094D01*
Y-41699D01*
X296040D01*
Y-41644D01*
X295986D01*
Y-41590D01*
X295932D01*
Y-41536D01*
Y-41482D01*
X295878D01*
Y-41428D01*
X295824D01*
Y-41374D01*
Y-41320D01*
X295770D01*
Y-41266D01*
X295715D01*
Y-41212D01*
Y-41158D01*
X295661D01*
Y-41104D01*
Y-41050D01*
X295607D01*
Y-40996D01*
Y-40942D01*
X295553D01*
Y-40888D01*
Y-40834D01*
X295499D01*
Y-40780D01*
Y-40725D01*
X295445D01*
Y-40671D01*
Y-40617D01*
Y-40563D01*
X295391D01*
Y-40509D01*
Y-40455D01*
Y-40401D01*
X295337D01*
Y-40347D01*
Y-40293D01*
Y-40239D01*
Y-40185D01*
X295283D01*
Y-40131D01*
Y-40077D01*
Y-40023D01*
Y-39968D01*
Y-39915D01*
Y-39860D01*
X295229D01*
Y-39806D01*
Y-39752D01*
Y-39698D01*
Y-39644D01*
Y-39590D01*
Y-39536D01*
Y-39482D01*
Y-39428D01*
Y-39374D01*
Y-39320D01*
Y-39266D01*
Y-39212D01*
Y-39158D01*
Y-39103D01*
Y-39050D01*
X295283D01*
Y-38995D01*
Y-38941D01*
Y-38887D01*
Y-38833D01*
Y-38779D01*
Y-38725D01*
X295337D01*
Y-38671D01*
Y-38617D01*
Y-38563D01*
Y-38509D01*
X295391D01*
Y-38455D01*
Y-38401D01*
Y-38347D01*
X295445D01*
Y-38293D01*
Y-38238D01*
Y-38184D01*
X295499D01*
Y-38130D01*
Y-38076D01*
X295553D01*
Y-38022D01*
Y-37968D01*
Y-37914D01*
X295607D01*
Y-37860D01*
Y-37806D01*
X295661D01*
Y-37752D01*
X295715D01*
Y-37698D01*
Y-37644D01*
X295770D01*
Y-37590D01*
Y-37536D01*
X295824D01*
Y-37482D01*
X295878D01*
Y-37428D01*
Y-37374D01*
X295932D01*
Y-37319D01*
X295986D01*
Y-37265D01*
X296040D01*
Y-37211D01*
Y-37157D01*
X296094D01*
Y-37103D01*
X296148D01*
Y-37049D01*
X296202D01*
Y-36995D01*
X296256D01*
Y-36941D01*
X296310D01*
Y-36887D01*
X296364D01*
Y-36833D01*
X296418D01*
Y-36779D01*
X296526D01*
Y-36725D01*
X296581D01*
Y-36671D01*
X296635D01*
Y-36617D01*
X296689D01*
Y-36563D01*
X296797D01*
Y-36509D01*
X296851D01*
Y-36454D01*
X296959D01*
Y-36400D01*
X297067D01*
Y-36346D01*
X297121D01*
Y-36292D01*
X297229D01*
Y-36238D01*
X297391D01*
Y-36184D01*
X297499D01*
Y-36130D01*
X297662D01*
Y-36076D01*
X297824D01*
Y-36022D01*
X298040D01*
Y-35968D01*
X298364D01*
Y-35914D01*
X299338D01*
Y-35968D01*
D02*
G37*
G36*
X393352Y-44942D02*
X393622D01*
Y-44996D01*
X393784D01*
Y-45050D01*
X393946D01*
Y-45104D01*
X394054D01*
Y-45158D01*
X394108D01*
Y-45213D01*
X394216D01*
Y-45267D01*
X394325D01*
Y-45321D01*
X394379D01*
Y-45375D01*
X394433D01*
Y-45429D01*
X394487D01*
Y-45483D01*
X394541D01*
Y-45537D01*
X394595D01*
Y-45591D01*
X394649D01*
Y-45645D01*
X394703D01*
Y-45699D01*
X394757D01*
Y-45753D01*
Y-45807D01*
X394811D01*
Y-45861D01*
X394865D01*
Y-45915D01*
Y-45969D01*
X394919D01*
Y-46023D01*
Y-46077D01*
X394973D01*
Y-46132D01*
Y-46186D01*
Y-46240D01*
X395027D01*
Y-46294D01*
Y-46348D01*
Y-46402D01*
X395081D01*
Y-46456D01*
Y-46510D01*
Y-46564D01*
Y-46618D01*
Y-46672D01*
X395135D01*
Y-46726D01*
Y-46780D01*
Y-46834D01*
Y-46889D01*
Y-46942D01*
Y-46997D01*
Y-47051D01*
Y-47105D01*
Y-47159D01*
Y-47213D01*
X395081D01*
Y-47267D01*
Y-47321D01*
Y-47375D01*
Y-47429D01*
Y-47483D01*
X395027D01*
Y-47537D01*
Y-47591D01*
Y-47645D01*
X394973D01*
Y-47699D01*
Y-47754D01*
X394919D01*
Y-47807D01*
Y-47862D01*
X394865D01*
Y-47916D01*
Y-47970D01*
X394811D01*
Y-48024D01*
Y-48078D01*
X394757D01*
Y-48132D01*
X394703D01*
Y-48186D01*
X394649D01*
Y-48240D01*
Y-48294D01*
X394595D01*
Y-48348D01*
X394541D01*
Y-48402D01*
X394487D01*
Y-48456D01*
X394379D01*
Y-48510D01*
X394325D01*
Y-48564D01*
X394270D01*
Y-48619D01*
X394162D01*
Y-48673D01*
X394054D01*
Y-48727D01*
X394000D01*
Y-48781D01*
X393838D01*
Y-48835D01*
X393676D01*
Y-48889D01*
X393514D01*
Y-48943D01*
X392703D01*
Y-48889D01*
X392487D01*
Y-48835D01*
X392378D01*
Y-48781D01*
X392216D01*
Y-48727D01*
X392108D01*
Y-48673D01*
X392054D01*
Y-48619D01*
X391946D01*
Y-48564D01*
X391892D01*
Y-48510D01*
X391784D01*
Y-48456D01*
X391730D01*
Y-48402D01*
X391675D01*
Y-48348D01*
X391621D01*
Y-48294D01*
X391567D01*
Y-48240D01*
X391513D01*
Y-48186D01*
Y-48132D01*
X391459D01*
Y-48078D01*
X391405D01*
Y-48024D01*
Y-47970D01*
X391351D01*
Y-47916D01*
X391297D01*
Y-47862D01*
Y-47807D01*
X391243D01*
Y-47754D01*
Y-47699D01*
Y-47645D01*
X391189D01*
Y-47591D01*
Y-47537D01*
Y-47483D01*
X391135D01*
Y-47429D01*
Y-47375D01*
Y-47321D01*
Y-47267D01*
X391081D01*
Y-47213D01*
Y-47159D01*
Y-47105D01*
Y-47051D01*
Y-46997D01*
Y-46942D01*
Y-46889D01*
Y-46834D01*
Y-46780D01*
Y-46726D01*
Y-46672D01*
Y-46618D01*
Y-46564D01*
X391135D01*
Y-46510D01*
Y-46456D01*
Y-46402D01*
Y-46348D01*
X391189D01*
Y-46294D01*
Y-46240D01*
Y-46186D01*
X391243D01*
Y-46132D01*
Y-46077D01*
X391297D01*
Y-46023D01*
Y-45969D01*
X391351D01*
Y-45915D01*
Y-45861D01*
X391405D01*
Y-45807D01*
X391459D01*
Y-45753D01*
Y-45699D01*
X391513D01*
Y-45645D01*
X391567D01*
Y-45591D01*
X391621D01*
Y-45537D01*
X391675D01*
Y-45483D01*
X391730D01*
Y-45429D01*
X391784D01*
Y-45375D01*
X391838D01*
Y-45321D01*
X391892D01*
Y-45267D01*
X392000D01*
Y-45213D01*
X392054D01*
Y-45158D01*
X392162D01*
Y-45104D01*
X392270D01*
Y-45050D01*
X392432D01*
Y-44996D01*
X392595D01*
Y-44942D01*
X392865D01*
Y-44888D01*
X393352D01*
Y-44942D01*
D02*
G37*
G36*
X393568Y-52295D02*
X393730D01*
Y-52349D01*
X393892D01*
Y-52403D01*
X394000D01*
Y-52457D01*
X394108D01*
Y-52511D01*
X394216D01*
Y-52565D01*
X394270D01*
Y-52619D01*
X394379D01*
Y-52673D01*
X394433D01*
Y-52727D01*
X394487D01*
Y-52781D01*
X394541D01*
Y-52835D01*
X394595D01*
Y-52889D01*
X394649D01*
Y-52943D01*
X394703D01*
Y-52997D01*
Y-53052D01*
X394757D01*
Y-53106D01*
X394811D01*
Y-53160D01*
Y-53214D01*
X394865D01*
Y-53268D01*
Y-53322D01*
X394919D01*
Y-53376D01*
Y-53430D01*
X394973D01*
Y-53484D01*
Y-53538D01*
X395027D01*
Y-53592D01*
Y-53646D01*
Y-53700D01*
X395081D01*
Y-53754D01*
Y-53808D01*
Y-53863D01*
Y-53917D01*
Y-53971D01*
X395135D01*
Y-54025D01*
Y-54079D01*
Y-54133D01*
Y-54187D01*
Y-54241D01*
Y-54295D01*
Y-54349D01*
Y-54403D01*
Y-54457D01*
Y-54511D01*
X395081D01*
Y-54565D01*
Y-54619D01*
Y-54673D01*
Y-54728D01*
Y-54782D01*
X395027D01*
Y-54836D01*
Y-54890D01*
Y-54944D01*
X394973D01*
Y-54998D01*
Y-55052D01*
X394919D01*
Y-55106D01*
Y-55160D01*
X394865D01*
Y-55214D01*
Y-55268D01*
X394811D01*
Y-55322D01*
Y-55376D01*
X394757D01*
Y-55430D01*
X394703D01*
Y-55484D01*
Y-55538D01*
X394649D01*
Y-55592D01*
X394595D01*
Y-55647D01*
X394541D01*
Y-55701D01*
X394487D01*
Y-55755D01*
X394433D01*
Y-55809D01*
X394325D01*
Y-55863D01*
X394270D01*
Y-55917D01*
X394216D01*
Y-55971D01*
X394108D01*
Y-56025D01*
X394000D01*
Y-56079D01*
X393892D01*
Y-56133D01*
X393730D01*
Y-56187D01*
X393568D01*
Y-56241D01*
X392649D01*
Y-56187D01*
X392487D01*
Y-56133D01*
X392324D01*
Y-56079D01*
X392216D01*
Y-56025D01*
X392108D01*
Y-55971D01*
X392000D01*
Y-55917D01*
X391946D01*
Y-55863D01*
X391838D01*
Y-55809D01*
X391784D01*
Y-55755D01*
X391730D01*
Y-55701D01*
X391675D01*
Y-55647D01*
X391621D01*
Y-55592D01*
X391567D01*
Y-55538D01*
X391513D01*
Y-55484D01*
X391459D01*
Y-55430D01*
Y-55376D01*
X391405D01*
Y-55322D01*
X391351D01*
Y-55268D01*
Y-55214D01*
X391297D01*
Y-55160D01*
Y-55106D01*
X391243D01*
Y-55052D01*
Y-54998D01*
X391189D01*
Y-54944D01*
Y-54890D01*
Y-54836D01*
X391135D01*
Y-54782D01*
Y-54728D01*
Y-54673D01*
Y-54619D01*
Y-54565D01*
X391081D01*
Y-54511D01*
Y-54457D01*
Y-54403D01*
Y-54349D01*
Y-54295D01*
Y-54241D01*
Y-54187D01*
Y-54133D01*
Y-54079D01*
Y-54025D01*
Y-53971D01*
Y-53917D01*
X391135D01*
Y-53863D01*
Y-53808D01*
Y-53754D01*
Y-53700D01*
Y-53646D01*
X391189D01*
Y-53592D01*
Y-53538D01*
Y-53484D01*
X391243D01*
Y-53430D01*
Y-53376D01*
X391297D01*
Y-53322D01*
Y-53268D01*
X391351D01*
Y-53214D01*
Y-53160D01*
X391405D01*
Y-53106D01*
X391459D01*
Y-53052D01*
Y-52997D01*
X391513D01*
Y-52943D01*
X391567D01*
Y-52889D01*
X391621D01*
Y-52835D01*
X391675D01*
Y-52781D01*
X391730D01*
Y-52727D01*
X391784D01*
Y-52673D01*
X391838D01*
Y-52619D01*
X391946D01*
Y-52565D01*
X392000D01*
Y-52511D01*
X392108D01*
Y-52457D01*
X392216D01*
Y-52403D01*
X392324D01*
Y-52349D01*
X392432D01*
Y-52295D01*
X392649D01*
Y-52241D01*
X393568D01*
Y-52295D01*
D02*
G37*
G36*
X407408Y-7748D02*
Y-7802D01*
Y-7856D01*
Y-7910D01*
Y-7964D01*
Y-8018D01*
Y-8072D01*
Y-8126D01*
Y-8180D01*
Y-8234D01*
Y-8288D01*
Y-8342D01*
Y-8396D01*
Y-8450D01*
Y-8504D01*
Y-8558D01*
Y-8613D01*
Y-8667D01*
Y-8721D01*
Y-8775D01*
Y-8829D01*
Y-8883D01*
Y-8937D01*
Y-8991D01*
Y-9045D01*
Y-9099D01*
Y-9153D01*
Y-9207D01*
Y-9261D01*
Y-9315D01*
Y-9369D01*
Y-9424D01*
Y-9478D01*
Y-9532D01*
Y-9586D01*
Y-9640D01*
Y-9694D01*
Y-9748D01*
X400542D01*
Y-9802D01*
X400325D01*
Y-9856D01*
X400217D01*
Y-9910D01*
X400109D01*
Y-9964D01*
X400001D01*
Y-10018D01*
X399947D01*
Y-10072D01*
X399839D01*
Y-10126D01*
X399785D01*
Y-10180D01*
X399731D01*
Y-10234D01*
X399677D01*
Y-10289D01*
Y-10343D01*
X399623D01*
Y-10397D01*
X399569D01*
Y-10451D01*
Y-10505D01*
X399515D01*
Y-10559D01*
Y-10613D01*
X399460D01*
Y-10667D01*
Y-10721D01*
X399406D01*
Y-10775D01*
Y-10829D01*
Y-10883D01*
Y-10937D01*
Y-10991D01*
X399352D01*
Y-11045D01*
Y-11099D01*
Y-11153D01*
Y-11208D01*
Y-11262D01*
Y-11316D01*
Y-11370D01*
Y-11424D01*
Y-11478D01*
Y-11532D01*
Y-11586D01*
Y-11640D01*
Y-11694D01*
Y-11748D01*
Y-11802D01*
Y-11856D01*
Y-11910D01*
Y-11964D01*
Y-12019D01*
Y-12072D01*
Y-12127D01*
Y-12181D01*
Y-12235D01*
Y-12289D01*
Y-12343D01*
Y-12397D01*
Y-12451D01*
Y-12505D01*
Y-12559D01*
Y-12613D01*
Y-12667D01*
Y-12721D01*
Y-12775D01*
Y-12829D01*
Y-12883D01*
Y-12937D01*
Y-12992D01*
Y-13046D01*
Y-13100D01*
Y-13154D01*
Y-13208D01*
Y-13262D01*
Y-13316D01*
Y-13370D01*
Y-13424D01*
Y-13478D01*
Y-13532D01*
Y-13586D01*
Y-13640D01*
Y-13694D01*
Y-13748D01*
Y-13803D01*
Y-13857D01*
Y-13911D01*
Y-13965D01*
Y-14019D01*
Y-14073D01*
Y-14127D01*
Y-14181D01*
Y-14235D01*
Y-14289D01*
Y-14343D01*
Y-14397D01*
Y-14451D01*
Y-14505D01*
Y-14559D01*
Y-14614D01*
Y-14668D01*
Y-14722D01*
Y-14776D01*
Y-14830D01*
Y-14884D01*
Y-14938D01*
Y-14992D01*
Y-15046D01*
Y-15100D01*
Y-15154D01*
Y-15208D01*
Y-15262D01*
Y-15316D01*
Y-15370D01*
Y-15424D01*
Y-15478D01*
Y-15532D01*
Y-15587D01*
Y-15641D01*
Y-15695D01*
Y-15749D01*
Y-15803D01*
Y-15857D01*
Y-15911D01*
Y-15965D01*
Y-16019D01*
Y-16073D01*
Y-16127D01*
Y-16181D01*
Y-16235D01*
Y-16289D01*
Y-16343D01*
Y-16398D01*
Y-16452D01*
Y-16506D01*
Y-16560D01*
Y-16614D01*
Y-16668D01*
Y-16722D01*
Y-16776D01*
Y-16830D01*
Y-16884D01*
Y-16938D01*
Y-16992D01*
Y-17046D01*
Y-17100D01*
Y-17154D01*
Y-17208D01*
Y-17263D01*
Y-17317D01*
Y-17371D01*
Y-17425D01*
Y-17479D01*
Y-17533D01*
Y-17587D01*
Y-17641D01*
Y-17695D01*
Y-17749D01*
Y-17803D01*
Y-17857D01*
Y-17911D01*
Y-17965D01*
Y-18019D01*
Y-18073D01*
Y-18127D01*
Y-18181D01*
Y-18236D01*
Y-18290D01*
Y-18344D01*
Y-18398D01*
Y-18452D01*
Y-18506D01*
Y-18560D01*
Y-18614D01*
Y-18668D01*
Y-18722D01*
Y-18776D01*
Y-18830D01*
Y-18884D01*
Y-18938D01*
Y-18993D01*
Y-19047D01*
Y-19101D01*
Y-19155D01*
Y-19209D01*
Y-19263D01*
Y-19317D01*
Y-19371D01*
Y-19425D01*
Y-19479D01*
Y-19533D01*
Y-19587D01*
Y-19641D01*
Y-19695D01*
Y-19749D01*
Y-19803D01*
Y-19858D01*
Y-19911D01*
Y-19966D01*
Y-20020D01*
Y-20074D01*
Y-20128D01*
Y-20182D01*
Y-20236D01*
Y-20290D01*
Y-20344D01*
Y-20398D01*
Y-20452D01*
Y-20506D01*
Y-20560D01*
Y-20614D01*
Y-20668D01*
Y-20722D01*
Y-20776D01*
Y-20831D01*
Y-20885D01*
Y-20939D01*
Y-20993D01*
Y-21047D01*
Y-21101D01*
Y-21155D01*
Y-21209D01*
Y-21263D01*
Y-21317D01*
Y-21371D01*
Y-21425D01*
Y-21479D01*
Y-21533D01*
Y-21587D01*
Y-21642D01*
Y-21696D01*
Y-21750D01*
Y-21804D01*
Y-21858D01*
Y-21912D01*
Y-21966D01*
Y-22020D01*
Y-22074D01*
Y-22128D01*
Y-22182D01*
Y-22236D01*
Y-22290D01*
Y-22344D01*
Y-22398D01*
Y-22452D01*
Y-22506D01*
Y-22561D01*
Y-22615D01*
Y-22669D01*
Y-22723D01*
Y-22777D01*
Y-22831D01*
Y-22885D01*
Y-22939D01*
Y-22993D01*
Y-23047D01*
Y-23101D01*
Y-23155D01*
Y-23209D01*
Y-23263D01*
Y-23317D01*
Y-23371D01*
Y-23426D01*
Y-23480D01*
Y-23534D01*
Y-23588D01*
Y-23642D01*
Y-23696D01*
Y-23750D01*
Y-23804D01*
Y-23858D01*
Y-23912D01*
Y-23966D01*
Y-24020D01*
Y-24074D01*
Y-24128D01*
Y-24182D01*
Y-24237D01*
Y-24291D01*
Y-24345D01*
Y-24399D01*
Y-24453D01*
Y-24507D01*
Y-24561D01*
Y-24615D01*
Y-24669D01*
Y-24723D01*
Y-24777D01*
Y-24831D01*
Y-24885D01*
Y-24939D01*
Y-24993D01*
Y-25047D01*
Y-25102D01*
Y-25155D01*
Y-25210D01*
Y-25264D01*
Y-25318D01*
Y-25372D01*
Y-25426D01*
Y-25480D01*
Y-25534D01*
Y-25588D01*
Y-25642D01*
Y-25696D01*
Y-25750D01*
Y-25804D01*
Y-25858D01*
Y-25912D01*
Y-25967D01*
Y-26021D01*
Y-26075D01*
Y-26129D01*
Y-26183D01*
Y-26237D01*
Y-26291D01*
Y-26345D01*
Y-26399D01*
Y-26453D01*
Y-26507D01*
Y-26561D01*
Y-26615D01*
Y-26669D01*
Y-26723D01*
Y-26777D01*
Y-26831D01*
Y-26886D01*
Y-26940D01*
Y-26994D01*
Y-27048D01*
Y-27102D01*
Y-27156D01*
Y-27210D01*
Y-27264D01*
Y-27318D01*
Y-27372D01*
Y-27426D01*
Y-27480D01*
Y-27534D01*
Y-27588D01*
Y-27642D01*
Y-27696D01*
Y-27751D01*
Y-27805D01*
Y-27859D01*
Y-27913D01*
Y-27967D01*
Y-28021D01*
Y-28075D01*
Y-28129D01*
Y-28183D01*
Y-28237D01*
Y-28291D01*
Y-28345D01*
Y-28399D01*
Y-28453D01*
Y-28507D01*
Y-28561D01*
Y-28615D01*
Y-28670D01*
Y-28724D01*
Y-28778D01*
Y-28832D01*
Y-28886D01*
Y-28940D01*
Y-28994D01*
Y-29048D01*
Y-29102D01*
Y-29156D01*
Y-29210D01*
Y-29264D01*
Y-29318D01*
Y-29372D01*
Y-29426D01*
Y-29480D01*
Y-29535D01*
Y-29589D01*
Y-29643D01*
Y-29697D01*
Y-29751D01*
Y-29805D01*
Y-29859D01*
Y-29913D01*
Y-29967D01*
Y-30021D01*
Y-30075D01*
Y-30129D01*
Y-30183D01*
Y-30237D01*
Y-30291D01*
Y-30345D01*
Y-30400D01*
Y-30454D01*
Y-30508D01*
Y-30562D01*
Y-30616D01*
Y-30670D01*
Y-30724D01*
Y-30778D01*
Y-30832D01*
Y-30886D01*
Y-30940D01*
Y-30994D01*
Y-31048D01*
Y-31102D01*
Y-31156D01*
Y-31211D01*
Y-31265D01*
Y-31319D01*
Y-31373D01*
Y-31427D01*
Y-31481D01*
Y-31535D01*
Y-31589D01*
Y-31643D01*
Y-31697D01*
Y-31751D01*
Y-31805D01*
Y-31859D01*
Y-31913D01*
Y-31967D01*
Y-32021D01*
Y-32076D01*
Y-32129D01*
Y-32184D01*
Y-32238D01*
Y-32292D01*
Y-32346D01*
Y-32400D01*
Y-32454D01*
Y-32508D01*
Y-32562D01*
Y-32616D01*
Y-32670D01*
Y-32724D01*
Y-32778D01*
Y-32832D01*
Y-32886D01*
Y-32941D01*
Y-32994D01*
Y-33049D01*
Y-33103D01*
Y-33157D01*
Y-33211D01*
Y-33265D01*
Y-33319D01*
Y-33373D01*
Y-33427D01*
Y-33481D01*
Y-33535D01*
Y-33589D01*
Y-33643D01*
Y-33697D01*
Y-33751D01*
Y-33806D01*
Y-33860D01*
Y-33914D01*
Y-33968D01*
Y-34022D01*
Y-34076D01*
Y-34130D01*
Y-34184D01*
Y-34238D01*
Y-34292D01*
Y-34346D01*
Y-34400D01*
Y-34454D01*
Y-34508D01*
Y-34562D01*
Y-34616D01*
Y-34670D01*
Y-34725D01*
Y-34779D01*
Y-34833D01*
Y-34887D01*
Y-34941D01*
Y-34995D01*
Y-35049D01*
Y-35103D01*
Y-35157D01*
Y-35211D01*
Y-35265D01*
Y-35319D01*
Y-35373D01*
Y-35427D01*
Y-35481D01*
Y-35535D01*
Y-35590D01*
Y-35644D01*
Y-35698D01*
Y-35752D01*
Y-35806D01*
Y-35860D01*
Y-35914D01*
Y-35968D01*
Y-36022D01*
Y-36076D01*
Y-36130D01*
Y-36184D01*
Y-36238D01*
Y-36292D01*
Y-36346D01*
Y-36400D01*
Y-36454D01*
Y-36509D01*
Y-36563D01*
Y-36617D01*
Y-36671D01*
Y-36725D01*
Y-36779D01*
Y-36833D01*
Y-36887D01*
Y-36941D01*
Y-36995D01*
Y-37049D01*
Y-37103D01*
Y-37157D01*
Y-37211D01*
Y-37265D01*
Y-37319D01*
Y-37374D01*
Y-37428D01*
Y-37482D01*
Y-37536D01*
Y-37590D01*
Y-37644D01*
Y-37698D01*
Y-37752D01*
Y-37806D01*
Y-37860D01*
Y-37914D01*
Y-37968D01*
Y-38022D01*
Y-38076D01*
Y-38130D01*
Y-38184D01*
Y-38238D01*
Y-38293D01*
Y-38347D01*
Y-38401D01*
Y-38455D01*
Y-38509D01*
Y-38563D01*
Y-38617D01*
Y-38671D01*
Y-38725D01*
Y-38779D01*
Y-38833D01*
Y-38887D01*
Y-38941D01*
Y-38995D01*
Y-39050D01*
Y-39103D01*
Y-39158D01*
Y-39212D01*
Y-39266D01*
Y-39320D01*
Y-39374D01*
Y-39428D01*
Y-39482D01*
Y-39536D01*
Y-39590D01*
Y-39644D01*
Y-39698D01*
Y-39752D01*
Y-39806D01*
Y-39860D01*
Y-39915D01*
Y-39968D01*
Y-40023D01*
Y-40077D01*
Y-40131D01*
Y-40185D01*
Y-40239D01*
Y-40293D01*
Y-40347D01*
Y-40401D01*
Y-40455D01*
Y-40509D01*
Y-40563D01*
Y-40617D01*
Y-40671D01*
Y-40725D01*
Y-40780D01*
Y-40834D01*
Y-40888D01*
Y-40942D01*
Y-40996D01*
Y-41050D01*
Y-41104D01*
Y-41158D01*
Y-41212D01*
Y-41266D01*
Y-41320D01*
Y-41374D01*
Y-41428D01*
Y-41482D01*
Y-41536D01*
Y-41590D01*
Y-41644D01*
Y-41699D01*
Y-41753D01*
Y-41807D01*
Y-41861D01*
Y-41915D01*
Y-41969D01*
Y-42023D01*
Y-42077D01*
Y-42131D01*
Y-42185D01*
Y-42239D01*
Y-42293D01*
Y-42347D01*
Y-42401D01*
Y-42455D01*
Y-42509D01*
Y-42564D01*
Y-42618D01*
Y-42672D01*
Y-42726D01*
Y-42780D01*
Y-42834D01*
Y-42888D01*
Y-42942D01*
Y-42996D01*
Y-43050D01*
Y-43104D01*
Y-43158D01*
Y-43212D01*
Y-43266D01*
Y-43320D01*
Y-43374D01*
Y-43429D01*
Y-43483D01*
Y-43537D01*
Y-43591D01*
Y-43645D01*
Y-43699D01*
Y-43753D01*
Y-43807D01*
Y-43861D01*
Y-43915D01*
Y-43969D01*
Y-44023D01*
Y-44077D01*
Y-44131D01*
Y-44185D01*
Y-44239D01*
Y-44293D01*
Y-44348D01*
Y-44402D01*
Y-44456D01*
Y-44510D01*
Y-44564D01*
Y-44618D01*
Y-44672D01*
Y-44726D01*
Y-44780D01*
Y-44834D01*
Y-44888D01*
Y-44942D01*
Y-44996D01*
Y-45050D01*
Y-45104D01*
Y-45158D01*
Y-45213D01*
Y-45267D01*
Y-45321D01*
Y-45375D01*
Y-45429D01*
Y-45483D01*
Y-45537D01*
Y-45591D01*
Y-45645D01*
Y-45699D01*
Y-45753D01*
Y-45807D01*
Y-45861D01*
Y-45915D01*
Y-45969D01*
Y-46023D01*
Y-46077D01*
Y-46132D01*
Y-46186D01*
Y-46240D01*
Y-46294D01*
Y-46348D01*
Y-46402D01*
Y-46456D01*
Y-46510D01*
Y-46564D01*
Y-46618D01*
Y-46672D01*
Y-46726D01*
Y-46780D01*
Y-46834D01*
Y-46889D01*
Y-46942D01*
Y-46997D01*
Y-47051D01*
Y-47105D01*
Y-47159D01*
Y-47213D01*
Y-47267D01*
Y-47321D01*
Y-47375D01*
Y-47429D01*
Y-47483D01*
Y-47537D01*
Y-47591D01*
Y-47645D01*
Y-47699D01*
Y-47754D01*
Y-47807D01*
Y-47862D01*
Y-47916D01*
Y-47970D01*
Y-48024D01*
Y-48078D01*
Y-48132D01*
Y-48186D01*
Y-48240D01*
Y-48294D01*
Y-48348D01*
Y-48402D01*
Y-48456D01*
Y-48510D01*
Y-48564D01*
Y-48619D01*
Y-48673D01*
Y-48727D01*
Y-48781D01*
Y-48835D01*
Y-48889D01*
Y-48943D01*
Y-48997D01*
Y-49051D01*
Y-49105D01*
Y-49159D01*
Y-49213D01*
Y-49267D01*
Y-49321D01*
Y-49375D01*
Y-49429D01*
Y-49483D01*
Y-49538D01*
Y-49592D01*
Y-49646D01*
Y-49700D01*
Y-49754D01*
Y-49808D01*
Y-49862D01*
Y-49916D01*
Y-49970D01*
Y-50024D01*
Y-50078D01*
Y-50132D01*
Y-50186D01*
Y-50240D01*
Y-50294D01*
Y-50348D01*
Y-50402D01*
Y-50457D01*
Y-50511D01*
Y-50565D01*
Y-50619D01*
Y-50673D01*
Y-50727D01*
Y-50781D01*
Y-50835D01*
Y-50889D01*
Y-50943D01*
Y-50997D01*
Y-51051D01*
Y-51105D01*
Y-51159D01*
Y-51213D01*
Y-51267D01*
Y-51322D01*
Y-51376D01*
Y-51430D01*
Y-51484D01*
Y-51538D01*
Y-51592D01*
Y-51646D01*
Y-51700D01*
Y-51754D01*
Y-51808D01*
Y-51862D01*
Y-51916D01*
Y-51970D01*
Y-52024D01*
Y-52078D01*
Y-52132D01*
Y-52187D01*
Y-52241D01*
Y-52295D01*
Y-52349D01*
Y-52403D01*
Y-52457D01*
Y-52511D01*
Y-52565D01*
Y-52619D01*
Y-52673D01*
Y-52727D01*
Y-52781D01*
Y-52835D01*
Y-52889D01*
Y-52943D01*
Y-52997D01*
Y-53052D01*
Y-53106D01*
Y-53160D01*
Y-53214D01*
Y-53268D01*
Y-53322D01*
Y-53376D01*
Y-53430D01*
Y-53484D01*
Y-53538D01*
Y-53592D01*
Y-53646D01*
Y-53700D01*
Y-53754D01*
Y-53808D01*
Y-53863D01*
Y-53917D01*
Y-53971D01*
Y-54025D01*
Y-54079D01*
Y-54133D01*
Y-54187D01*
Y-54241D01*
Y-54295D01*
Y-54349D01*
Y-54403D01*
Y-54457D01*
Y-54511D01*
Y-54565D01*
Y-54619D01*
Y-54673D01*
Y-54728D01*
Y-54782D01*
Y-54836D01*
Y-54890D01*
Y-54944D01*
Y-54998D01*
Y-55052D01*
Y-55106D01*
Y-55160D01*
Y-55214D01*
Y-55268D01*
Y-55322D01*
Y-55376D01*
Y-55430D01*
Y-55484D01*
Y-55538D01*
Y-55592D01*
Y-55647D01*
Y-55701D01*
Y-55755D01*
Y-55809D01*
Y-55863D01*
Y-55917D01*
Y-55971D01*
Y-56025D01*
Y-56079D01*
Y-56133D01*
Y-56187D01*
Y-56241D01*
Y-56295D01*
Y-56349D01*
Y-56403D01*
Y-56457D01*
Y-56511D01*
Y-56566D01*
Y-56620D01*
Y-56674D01*
Y-56728D01*
Y-56782D01*
Y-56836D01*
Y-56890D01*
Y-56944D01*
Y-56998D01*
Y-57052D01*
Y-57106D01*
Y-57160D01*
Y-57214D01*
Y-57268D01*
Y-57322D01*
Y-57376D01*
Y-57431D01*
Y-57485D01*
Y-57539D01*
Y-57593D01*
Y-57647D01*
Y-57701D01*
Y-57755D01*
Y-57809D01*
Y-57863D01*
Y-57917D01*
Y-57971D01*
Y-58025D01*
Y-58079D01*
Y-58133D01*
Y-58187D01*
Y-58241D01*
Y-58296D01*
Y-58350D01*
Y-58404D01*
Y-58458D01*
Y-58512D01*
Y-58566D01*
Y-58620D01*
Y-58674D01*
Y-58728D01*
Y-58782D01*
Y-58836D01*
Y-58890D01*
Y-58944D01*
Y-58998D01*
Y-59052D01*
Y-59106D01*
Y-59161D01*
Y-59215D01*
Y-59269D01*
Y-59323D01*
Y-59377D01*
Y-59431D01*
Y-59485D01*
Y-59539D01*
Y-59593D01*
Y-59647D01*
Y-59701D01*
Y-59755D01*
Y-59809D01*
Y-59863D01*
Y-59917D01*
Y-59971D01*
Y-60026D01*
Y-60080D01*
Y-60134D01*
Y-60188D01*
Y-60242D01*
Y-60296D01*
Y-60350D01*
Y-60404D01*
Y-60458D01*
Y-60512D01*
Y-60566D01*
Y-60620D01*
Y-60674D01*
Y-60728D01*
Y-60782D01*
Y-60836D01*
Y-60891D01*
Y-60945D01*
Y-60999D01*
Y-61053D01*
Y-61107D01*
Y-61161D01*
Y-61215D01*
Y-61269D01*
Y-61323D01*
Y-61377D01*
Y-61431D01*
Y-61485D01*
Y-61539D01*
Y-61593D01*
Y-61647D01*
Y-61702D01*
Y-61756D01*
Y-61810D01*
Y-61864D01*
Y-61918D01*
Y-61972D01*
Y-62026D01*
Y-62080D01*
Y-62134D01*
Y-62188D01*
Y-62242D01*
Y-62296D01*
Y-62350D01*
Y-62404D01*
Y-62458D01*
Y-62512D01*
Y-62566D01*
Y-62621D01*
Y-62675D01*
Y-62729D01*
Y-62783D01*
Y-62837D01*
Y-62891D01*
Y-62945D01*
Y-62999D01*
Y-63053D01*
Y-63107D01*
Y-63161D01*
Y-63215D01*
Y-63269D01*
Y-63323D01*
Y-63377D01*
Y-63431D01*
Y-63485D01*
Y-63540D01*
Y-63594D01*
Y-63648D01*
Y-63702D01*
Y-63756D01*
Y-63810D01*
Y-63864D01*
Y-63918D01*
Y-63972D01*
Y-64026D01*
Y-64080D01*
Y-64134D01*
Y-64188D01*
Y-64242D01*
Y-64296D01*
Y-64350D01*
Y-64405D01*
Y-64459D01*
Y-64513D01*
Y-64567D01*
Y-64621D01*
Y-64675D01*
Y-64729D01*
Y-64783D01*
Y-64837D01*
Y-64891D01*
Y-64945D01*
Y-64999D01*
Y-65053D01*
Y-65107D01*
Y-65161D01*
Y-65215D01*
Y-65270D01*
Y-65324D01*
Y-65378D01*
Y-65432D01*
Y-65486D01*
Y-65540D01*
Y-65594D01*
Y-65648D01*
Y-65702D01*
Y-65756D01*
Y-65810D01*
Y-65864D01*
Y-65918D01*
Y-65972D01*
Y-66026D01*
Y-66080D01*
Y-66135D01*
Y-66189D01*
Y-66243D01*
Y-66297D01*
Y-66351D01*
Y-66405D01*
Y-66459D01*
Y-66513D01*
Y-66567D01*
Y-66621D01*
Y-66675D01*
Y-66729D01*
Y-66783D01*
Y-66837D01*
Y-66891D01*
Y-66945D01*
Y-67000D01*
Y-67054D01*
Y-67108D01*
Y-67162D01*
Y-67216D01*
Y-67270D01*
Y-67324D01*
Y-67378D01*
Y-67432D01*
Y-67486D01*
Y-67540D01*
Y-67594D01*
Y-67648D01*
Y-67702D01*
Y-67756D01*
Y-67810D01*
Y-67865D01*
Y-67919D01*
Y-67973D01*
Y-68027D01*
Y-68081D01*
Y-68135D01*
Y-68189D01*
Y-68243D01*
Y-68297D01*
Y-68351D01*
Y-68405D01*
Y-68459D01*
Y-68513D01*
Y-68567D01*
Y-68621D01*
Y-68676D01*
Y-68730D01*
Y-68784D01*
Y-68838D01*
Y-68892D01*
Y-68946D01*
Y-69000D01*
Y-69054D01*
Y-69108D01*
Y-69162D01*
Y-69216D01*
Y-69270D01*
Y-69324D01*
Y-69378D01*
Y-69432D01*
Y-69486D01*
X397352D01*
Y-69432D01*
Y-69378D01*
Y-69324D01*
Y-69270D01*
Y-69216D01*
Y-69162D01*
Y-69108D01*
Y-69054D01*
Y-69000D01*
Y-68946D01*
Y-68892D01*
Y-68838D01*
Y-68784D01*
Y-68730D01*
Y-68676D01*
Y-68621D01*
Y-68567D01*
Y-68513D01*
Y-68459D01*
Y-68405D01*
Y-68351D01*
Y-68297D01*
Y-68243D01*
Y-68189D01*
Y-68135D01*
Y-68081D01*
Y-68027D01*
Y-67973D01*
Y-67919D01*
Y-67865D01*
Y-67810D01*
Y-67756D01*
Y-67702D01*
Y-67648D01*
Y-67594D01*
Y-67540D01*
Y-67486D01*
Y-67432D01*
Y-67378D01*
Y-67324D01*
Y-67270D01*
Y-67216D01*
Y-67162D01*
Y-67108D01*
Y-67054D01*
Y-67000D01*
Y-66945D01*
Y-66891D01*
Y-66837D01*
Y-66783D01*
Y-66729D01*
Y-66675D01*
Y-66621D01*
Y-66567D01*
Y-66513D01*
Y-66459D01*
Y-66405D01*
Y-66351D01*
Y-66297D01*
Y-66243D01*
Y-66189D01*
Y-66135D01*
Y-66080D01*
Y-66026D01*
Y-65972D01*
Y-65918D01*
Y-65864D01*
Y-65810D01*
Y-65756D01*
Y-65702D01*
Y-65648D01*
Y-65594D01*
Y-65540D01*
Y-65486D01*
Y-65432D01*
Y-65378D01*
Y-65324D01*
Y-65270D01*
Y-65215D01*
Y-65161D01*
Y-65107D01*
Y-65053D01*
Y-64999D01*
Y-64945D01*
Y-64891D01*
Y-64837D01*
Y-64783D01*
Y-64729D01*
Y-64675D01*
Y-64621D01*
Y-64567D01*
Y-64513D01*
Y-64459D01*
Y-64405D01*
Y-64350D01*
Y-64296D01*
Y-64242D01*
Y-64188D01*
Y-64134D01*
Y-64080D01*
Y-64026D01*
Y-63972D01*
Y-63918D01*
Y-63864D01*
Y-63810D01*
Y-63756D01*
Y-63702D01*
Y-63648D01*
Y-63594D01*
Y-63540D01*
Y-63485D01*
Y-63431D01*
Y-63377D01*
Y-63323D01*
Y-63269D01*
Y-63215D01*
Y-63161D01*
Y-63107D01*
Y-63053D01*
Y-62999D01*
Y-62945D01*
Y-62891D01*
Y-62837D01*
Y-62783D01*
Y-62729D01*
Y-62675D01*
Y-62621D01*
Y-62566D01*
Y-62512D01*
Y-62458D01*
Y-62404D01*
Y-62350D01*
Y-62296D01*
Y-62242D01*
Y-62188D01*
Y-62134D01*
Y-62080D01*
Y-62026D01*
Y-61972D01*
Y-61918D01*
Y-61864D01*
Y-61810D01*
Y-61756D01*
Y-61702D01*
Y-61647D01*
Y-61593D01*
Y-61539D01*
Y-61485D01*
Y-61431D01*
Y-61377D01*
Y-61323D01*
Y-61269D01*
Y-61215D01*
Y-61161D01*
Y-61107D01*
Y-61053D01*
Y-60999D01*
Y-60945D01*
Y-60891D01*
Y-60836D01*
Y-60782D01*
Y-60728D01*
Y-60674D01*
Y-60620D01*
Y-60566D01*
Y-60512D01*
Y-60458D01*
Y-60404D01*
Y-60350D01*
Y-60296D01*
Y-60242D01*
Y-60188D01*
Y-60134D01*
Y-60080D01*
Y-60026D01*
Y-59971D01*
Y-59917D01*
Y-59863D01*
Y-59809D01*
Y-59755D01*
Y-59701D01*
Y-59647D01*
Y-59593D01*
Y-59539D01*
Y-59485D01*
Y-59431D01*
Y-59377D01*
Y-59323D01*
Y-59269D01*
Y-59215D01*
Y-59161D01*
Y-59106D01*
Y-59052D01*
Y-58998D01*
Y-58944D01*
Y-58890D01*
Y-58836D01*
Y-58782D01*
Y-58728D01*
Y-58674D01*
Y-58620D01*
Y-58566D01*
Y-58512D01*
Y-58458D01*
Y-58404D01*
Y-58350D01*
Y-58296D01*
Y-58241D01*
Y-58187D01*
Y-58133D01*
Y-58079D01*
Y-58025D01*
Y-57971D01*
Y-57917D01*
Y-57863D01*
Y-57809D01*
Y-57755D01*
Y-57701D01*
Y-57647D01*
Y-57593D01*
Y-57539D01*
Y-57485D01*
Y-57431D01*
Y-57376D01*
Y-57322D01*
Y-57268D01*
Y-57214D01*
Y-57160D01*
Y-57106D01*
Y-57052D01*
Y-56998D01*
Y-56944D01*
Y-56890D01*
Y-56836D01*
Y-56782D01*
Y-56728D01*
Y-56674D01*
Y-56620D01*
Y-56566D01*
Y-56511D01*
Y-56457D01*
Y-56403D01*
Y-56349D01*
Y-56295D01*
Y-56241D01*
Y-56187D01*
Y-56133D01*
Y-56079D01*
Y-56025D01*
Y-55971D01*
Y-55917D01*
Y-55863D01*
Y-55809D01*
Y-55755D01*
Y-55701D01*
Y-55647D01*
Y-55592D01*
Y-55538D01*
Y-55484D01*
Y-55430D01*
Y-55376D01*
Y-55322D01*
Y-55268D01*
Y-55214D01*
Y-55160D01*
Y-55106D01*
Y-55052D01*
Y-54998D01*
Y-54944D01*
Y-54890D01*
Y-54836D01*
Y-54782D01*
Y-54728D01*
Y-54673D01*
Y-54619D01*
Y-54565D01*
Y-54511D01*
Y-54457D01*
Y-54403D01*
Y-54349D01*
Y-54295D01*
Y-54241D01*
Y-54187D01*
Y-54133D01*
Y-54079D01*
Y-54025D01*
Y-53971D01*
Y-53917D01*
Y-53863D01*
Y-53808D01*
Y-53754D01*
Y-53700D01*
Y-53646D01*
Y-53592D01*
Y-53538D01*
Y-53484D01*
Y-53430D01*
Y-53376D01*
Y-53322D01*
Y-53268D01*
Y-53214D01*
Y-53160D01*
Y-53106D01*
Y-53052D01*
Y-52997D01*
Y-52943D01*
Y-52889D01*
Y-52835D01*
Y-52781D01*
Y-52727D01*
Y-52673D01*
Y-52619D01*
Y-52565D01*
Y-52511D01*
Y-52457D01*
Y-52403D01*
Y-52349D01*
Y-52295D01*
Y-52241D01*
Y-52187D01*
Y-52132D01*
Y-52078D01*
Y-52024D01*
Y-51970D01*
Y-51916D01*
Y-51862D01*
Y-51808D01*
Y-51754D01*
Y-51700D01*
Y-51646D01*
Y-51592D01*
Y-51538D01*
Y-51484D01*
Y-51430D01*
Y-51376D01*
Y-51322D01*
Y-51267D01*
Y-51213D01*
Y-51159D01*
Y-51105D01*
Y-51051D01*
Y-50997D01*
Y-50943D01*
Y-50889D01*
Y-50835D01*
Y-50781D01*
Y-50727D01*
Y-50673D01*
Y-50619D01*
Y-50565D01*
Y-50511D01*
Y-50457D01*
Y-50402D01*
Y-50348D01*
Y-50294D01*
Y-50240D01*
Y-50186D01*
Y-50132D01*
Y-50078D01*
Y-50024D01*
Y-49970D01*
Y-49916D01*
Y-49862D01*
Y-49808D01*
Y-49754D01*
Y-49700D01*
Y-49646D01*
Y-49592D01*
Y-49538D01*
Y-49483D01*
Y-49429D01*
Y-49375D01*
Y-49321D01*
Y-49267D01*
Y-49213D01*
Y-49159D01*
Y-49105D01*
Y-49051D01*
Y-48997D01*
Y-48943D01*
Y-48889D01*
Y-48835D01*
Y-48781D01*
Y-48727D01*
Y-48673D01*
Y-48619D01*
Y-48564D01*
Y-48510D01*
Y-48456D01*
Y-48402D01*
Y-48348D01*
Y-48294D01*
Y-48240D01*
Y-48186D01*
Y-48132D01*
Y-48078D01*
Y-48024D01*
Y-47970D01*
Y-47916D01*
Y-47862D01*
Y-47807D01*
Y-47754D01*
Y-47699D01*
Y-47645D01*
Y-47591D01*
Y-47537D01*
Y-47483D01*
Y-47429D01*
Y-47375D01*
Y-47321D01*
Y-47267D01*
Y-47213D01*
Y-47159D01*
Y-47105D01*
Y-47051D01*
Y-46997D01*
Y-46942D01*
Y-46889D01*
Y-46834D01*
Y-46780D01*
Y-46726D01*
Y-46672D01*
Y-46618D01*
Y-46564D01*
Y-46510D01*
Y-46456D01*
Y-46402D01*
Y-46348D01*
Y-46294D01*
Y-46240D01*
Y-46186D01*
Y-46132D01*
Y-46077D01*
Y-46023D01*
Y-45969D01*
Y-45915D01*
Y-45861D01*
Y-45807D01*
Y-45753D01*
Y-45699D01*
Y-45645D01*
Y-45591D01*
Y-45537D01*
Y-45483D01*
Y-45429D01*
Y-45375D01*
Y-45321D01*
Y-45267D01*
Y-45213D01*
Y-45158D01*
Y-45104D01*
Y-45050D01*
Y-44996D01*
Y-44942D01*
Y-44888D01*
Y-44834D01*
Y-44780D01*
Y-44726D01*
Y-44672D01*
Y-44618D01*
Y-44564D01*
Y-44510D01*
Y-44456D01*
Y-44402D01*
Y-44348D01*
Y-44293D01*
Y-44239D01*
Y-44185D01*
Y-44131D01*
Y-44077D01*
Y-44023D01*
Y-43969D01*
Y-43915D01*
Y-43861D01*
Y-43807D01*
Y-43753D01*
Y-43699D01*
Y-43645D01*
Y-43591D01*
Y-43537D01*
Y-43483D01*
Y-43429D01*
Y-43374D01*
Y-43320D01*
Y-43266D01*
Y-43212D01*
Y-43158D01*
Y-43104D01*
Y-43050D01*
Y-42996D01*
Y-42942D01*
Y-42888D01*
Y-42834D01*
Y-42780D01*
Y-42726D01*
Y-42672D01*
Y-42618D01*
Y-42564D01*
Y-42509D01*
Y-42455D01*
Y-42401D01*
Y-42347D01*
Y-42293D01*
Y-42239D01*
Y-42185D01*
Y-42131D01*
Y-42077D01*
Y-42023D01*
Y-41969D01*
Y-41915D01*
Y-41861D01*
Y-41807D01*
Y-41753D01*
Y-41699D01*
Y-41644D01*
Y-41590D01*
Y-41536D01*
Y-41482D01*
Y-41428D01*
Y-41374D01*
Y-41320D01*
Y-41266D01*
Y-41212D01*
Y-41158D01*
Y-41104D01*
Y-41050D01*
Y-40996D01*
Y-40942D01*
Y-40888D01*
Y-40834D01*
Y-40780D01*
Y-40725D01*
Y-40671D01*
Y-40617D01*
Y-40563D01*
Y-40509D01*
Y-40455D01*
Y-40401D01*
Y-40347D01*
Y-40293D01*
Y-40239D01*
Y-40185D01*
Y-40131D01*
Y-40077D01*
Y-40023D01*
Y-39968D01*
Y-39915D01*
Y-39860D01*
Y-39806D01*
Y-39752D01*
Y-39698D01*
Y-39644D01*
Y-39590D01*
Y-39536D01*
Y-39482D01*
Y-39428D01*
Y-39374D01*
Y-39320D01*
Y-39266D01*
Y-39212D01*
Y-39158D01*
Y-39103D01*
Y-39050D01*
Y-38995D01*
Y-38941D01*
Y-38887D01*
Y-38833D01*
Y-38779D01*
Y-38725D01*
Y-38671D01*
Y-38617D01*
Y-38563D01*
Y-38509D01*
Y-38455D01*
Y-38401D01*
Y-38347D01*
Y-38293D01*
Y-38238D01*
Y-38184D01*
Y-38130D01*
Y-38076D01*
Y-38022D01*
Y-37968D01*
Y-37914D01*
Y-37860D01*
Y-37806D01*
Y-37752D01*
Y-37698D01*
Y-37644D01*
Y-37590D01*
Y-37536D01*
Y-37482D01*
Y-37428D01*
Y-37374D01*
Y-37319D01*
Y-37265D01*
Y-37211D01*
Y-37157D01*
Y-37103D01*
Y-37049D01*
Y-36995D01*
Y-36941D01*
Y-36887D01*
Y-36833D01*
Y-36779D01*
Y-36725D01*
Y-36671D01*
Y-36617D01*
Y-36563D01*
Y-36509D01*
Y-36454D01*
Y-36400D01*
Y-36346D01*
Y-36292D01*
Y-36238D01*
Y-36184D01*
Y-36130D01*
Y-36076D01*
Y-36022D01*
Y-35968D01*
Y-35914D01*
Y-35860D01*
Y-35806D01*
Y-35752D01*
Y-35698D01*
Y-35644D01*
Y-35590D01*
Y-35535D01*
Y-35481D01*
Y-35427D01*
Y-35373D01*
Y-35319D01*
Y-35265D01*
Y-35211D01*
Y-35157D01*
Y-35103D01*
Y-35049D01*
Y-34995D01*
Y-34941D01*
Y-34887D01*
Y-34833D01*
Y-34779D01*
Y-34725D01*
Y-34670D01*
Y-34616D01*
Y-34562D01*
Y-34508D01*
Y-34454D01*
Y-34400D01*
Y-34346D01*
Y-34292D01*
Y-34238D01*
Y-34184D01*
Y-34130D01*
Y-34076D01*
Y-34022D01*
Y-33968D01*
Y-33914D01*
Y-33860D01*
Y-33806D01*
Y-33751D01*
Y-33697D01*
Y-33643D01*
Y-33589D01*
Y-33535D01*
Y-33481D01*
Y-33427D01*
Y-33373D01*
Y-33319D01*
Y-33265D01*
Y-33211D01*
Y-33157D01*
Y-33103D01*
Y-33049D01*
Y-32994D01*
Y-32941D01*
Y-32886D01*
Y-32832D01*
Y-32778D01*
Y-32724D01*
Y-32670D01*
Y-32616D01*
Y-32562D01*
Y-32508D01*
Y-32454D01*
Y-32400D01*
Y-32346D01*
Y-32292D01*
Y-32238D01*
Y-32184D01*
Y-32129D01*
Y-32076D01*
Y-32021D01*
Y-31967D01*
Y-31913D01*
Y-31859D01*
Y-31805D01*
Y-31751D01*
Y-31697D01*
Y-31643D01*
Y-31589D01*
Y-31535D01*
Y-31481D01*
Y-31427D01*
Y-31373D01*
Y-31319D01*
Y-31265D01*
Y-31211D01*
Y-31156D01*
Y-31102D01*
Y-31048D01*
Y-30994D01*
Y-30940D01*
Y-30886D01*
Y-30832D01*
Y-30778D01*
Y-30724D01*
Y-30670D01*
Y-30616D01*
Y-30562D01*
Y-30508D01*
Y-30454D01*
Y-30400D01*
Y-30345D01*
Y-30291D01*
Y-30237D01*
Y-30183D01*
Y-30129D01*
Y-30075D01*
Y-30021D01*
Y-29967D01*
Y-29913D01*
Y-29859D01*
Y-29805D01*
Y-29751D01*
Y-29697D01*
Y-29643D01*
Y-29589D01*
Y-29535D01*
Y-29480D01*
Y-29426D01*
Y-29372D01*
Y-29318D01*
Y-29264D01*
Y-29210D01*
Y-29156D01*
Y-29102D01*
Y-29048D01*
Y-28994D01*
Y-28940D01*
Y-28886D01*
Y-28832D01*
Y-28778D01*
Y-28724D01*
Y-28670D01*
Y-28615D01*
Y-28561D01*
Y-28507D01*
Y-28453D01*
Y-28399D01*
Y-28345D01*
Y-28291D01*
Y-28237D01*
Y-28183D01*
Y-28129D01*
Y-28075D01*
Y-28021D01*
Y-27967D01*
Y-27913D01*
Y-27859D01*
Y-27805D01*
Y-27751D01*
Y-27696D01*
Y-27642D01*
Y-27588D01*
Y-27534D01*
Y-27480D01*
Y-27426D01*
Y-27372D01*
Y-27318D01*
Y-27264D01*
Y-27210D01*
Y-27156D01*
Y-27102D01*
Y-27048D01*
Y-26994D01*
Y-26940D01*
Y-26886D01*
Y-26831D01*
Y-26777D01*
Y-26723D01*
Y-26669D01*
Y-26615D01*
Y-26561D01*
Y-26507D01*
Y-26453D01*
Y-26399D01*
Y-26345D01*
Y-26291D01*
Y-26237D01*
Y-26183D01*
Y-26129D01*
Y-26075D01*
Y-26021D01*
Y-25967D01*
Y-25912D01*
Y-25858D01*
Y-25804D01*
Y-25750D01*
Y-25696D01*
Y-25642D01*
Y-25588D01*
Y-25534D01*
Y-25480D01*
Y-25426D01*
Y-25372D01*
Y-25318D01*
Y-25264D01*
Y-25210D01*
Y-25155D01*
Y-25102D01*
Y-25047D01*
Y-24993D01*
Y-24939D01*
Y-24885D01*
Y-24831D01*
Y-24777D01*
Y-24723D01*
Y-24669D01*
Y-24615D01*
Y-24561D01*
Y-24507D01*
Y-24453D01*
Y-24399D01*
Y-24345D01*
Y-24291D01*
Y-24237D01*
Y-24182D01*
Y-24128D01*
Y-24074D01*
Y-24020D01*
Y-23966D01*
Y-23912D01*
Y-23858D01*
Y-23804D01*
Y-23750D01*
Y-23696D01*
Y-23642D01*
Y-23588D01*
Y-23534D01*
Y-23480D01*
Y-23426D01*
Y-23371D01*
Y-23317D01*
Y-23263D01*
Y-23209D01*
Y-23155D01*
Y-23101D01*
Y-23047D01*
Y-22993D01*
Y-22939D01*
Y-22885D01*
Y-22831D01*
Y-22777D01*
Y-22723D01*
Y-22669D01*
Y-22615D01*
Y-22561D01*
Y-22506D01*
Y-22452D01*
Y-22398D01*
Y-22344D01*
Y-22290D01*
Y-22236D01*
Y-22182D01*
Y-22128D01*
Y-22074D01*
Y-22020D01*
Y-21966D01*
Y-21912D01*
Y-21858D01*
Y-21804D01*
Y-21750D01*
Y-21696D01*
Y-21642D01*
Y-21587D01*
Y-21533D01*
Y-21479D01*
Y-21425D01*
Y-21371D01*
Y-21317D01*
Y-21263D01*
Y-21209D01*
Y-21155D01*
Y-21101D01*
Y-21047D01*
Y-20993D01*
Y-20939D01*
Y-20885D01*
Y-20831D01*
Y-20776D01*
Y-20722D01*
Y-20668D01*
Y-20614D01*
Y-20560D01*
Y-20506D01*
Y-20452D01*
Y-20398D01*
Y-20344D01*
Y-20290D01*
Y-20236D01*
Y-20182D01*
Y-20128D01*
Y-20074D01*
Y-20020D01*
Y-19966D01*
Y-19911D01*
Y-19858D01*
Y-19803D01*
Y-19749D01*
Y-19695D01*
Y-19641D01*
Y-19587D01*
Y-19533D01*
Y-19479D01*
Y-19425D01*
Y-19371D01*
Y-19317D01*
Y-19263D01*
Y-19209D01*
Y-19155D01*
Y-19101D01*
Y-19047D01*
Y-18993D01*
Y-18938D01*
Y-18884D01*
Y-18830D01*
Y-18776D01*
Y-18722D01*
Y-18668D01*
Y-18614D01*
Y-18560D01*
Y-18506D01*
Y-18452D01*
Y-18398D01*
Y-18344D01*
Y-18290D01*
Y-18236D01*
Y-18181D01*
Y-18127D01*
Y-18073D01*
Y-18019D01*
Y-17965D01*
Y-17911D01*
Y-17857D01*
Y-17803D01*
Y-17749D01*
Y-17695D01*
Y-17641D01*
Y-17587D01*
Y-17533D01*
Y-17479D01*
Y-17425D01*
Y-17371D01*
Y-17317D01*
Y-17263D01*
Y-17208D01*
Y-17154D01*
Y-17100D01*
Y-17046D01*
Y-16992D01*
Y-16938D01*
Y-16884D01*
Y-16830D01*
Y-16776D01*
Y-16722D01*
Y-16668D01*
Y-16614D01*
Y-16560D01*
Y-16506D01*
Y-16452D01*
Y-16398D01*
Y-16343D01*
Y-16289D01*
Y-16235D01*
Y-16181D01*
Y-16127D01*
Y-16073D01*
Y-16019D01*
Y-15965D01*
Y-15911D01*
Y-15857D01*
Y-15803D01*
Y-15749D01*
Y-15695D01*
Y-15641D01*
Y-15587D01*
Y-15532D01*
Y-15478D01*
Y-15424D01*
Y-15370D01*
Y-15316D01*
Y-15262D01*
Y-15208D01*
Y-15154D01*
Y-15100D01*
Y-15046D01*
Y-14992D01*
Y-14938D01*
Y-14884D01*
Y-14830D01*
Y-14776D01*
Y-14722D01*
Y-14668D01*
Y-14614D01*
Y-14559D01*
Y-14505D01*
Y-14451D01*
Y-14397D01*
Y-14343D01*
Y-14289D01*
Y-14235D01*
Y-14181D01*
Y-14127D01*
Y-14073D01*
Y-14019D01*
Y-13965D01*
Y-13911D01*
Y-13857D01*
Y-13803D01*
Y-13748D01*
Y-13694D01*
Y-13640D01*
Y-13586D01*
Y-13532D01*
Y-13478D01*
Y-13424D01*
Y-13370D01*
Y-13316D01*
Y-13262D01*
Y-13208D01*
Y-13154D01*
Y-13100D01*
Y-13046D01*
Y-12992D01*
Y-12937D01*
Y-12883D01*
Y-12829D01*
Y-12775D01*
Y-12721D01*
Y-12667D01*
Y-12613D01*
Y-12559D01*
Y-12505D01*
Y-12451D01*
Y-12397D01*
Y-12343D01*
Y-12289D01*
Y-12235D01*
Y-12181D01*
Y-12127D01*
Y-12072D01*
Y-12019D01*
Y-11964D01*
Y-11910D01*
Y-11856D01*
Y-11802D01*
Y-11748D01*
Y-11694D01*
Y-11640D01*
Y-11586D01*
Y-11532D01*
Y-11478D01*
Y-11424D01*
Y-11370D01*
Y-11316D01*
Y-11262D01*
Y-11208D01*
Y-11153D01*
Y-11099D01*
Y-11045D01*
Y-10991D01*
Y-10937D01*
Y-10883D01*
Y-10829D01*
Y-10775D01*
Y-10721D01*
Y-10667D01*
Y-10613D01*
Y-10559D01*
Y-10505D01*
Y-10451D01*
X397406D01*
Y-10397D01*
Y-10343D01*
Y-10289D01*
Y-10234D01*
Y-10180D01*
X397460D01*
Y-10126D01*
Y-10072D01*
Y-10018D01*
Y-9964D01*
X397514D01*
Y-9910D01*
Y-9856D01*
X397568D01*
Y-9802D01*
Y-9748D01*
Y-9694D01*
X397622D01*
Y-9640D01*
Y-9586D01*
X397676D01*
Y-9532D01*
Y-9478D01*
X397730D01*
Y-9424D01*
Y-9369D01*
X397784D01*
Y-9315D01*
Y-9261D01*
X397839D01*
Y-9207D01*
X397893D01*
Y-9153D01*
Y-9099D01*
X397947D01*
Y-9045D01*
X398001D01*
Y-8991D01*
X398055D01*
Y-8937D01*
Y-8883D01*
X398109D01*
Y-8829D01*
X398163D01*
Y-8775D01*
X398217D01*
Y-8721D01*
X398271D01*
Y-8667D01*
X398325D01*
Y-8613D01*
X398379D01*
Y-8558D01*
X398433D01*
Y-8504D01*
X398487D01*
Y-8450D01*
X398595D01*
Y-8396D01*
X398650D01*
Y-8342D01*
X398704D01*
Y-8288D01*
X398812D01*
Y-8234D01*
X398866D01*
Y-8180D01*
X398974D01*
Y-8126D01*
X399082D01*
Y-8072D01*
X399190D01*
Y-8018D01*
X399298D01*
Y-7964D01*
X399460D01*
Y-7910D01*
X399569D01*
Y-7856D01*
X399785D01*
Y-7802D01*
X400001D01*
Y-7748D01*
X400542D01*
Y-7694D01*
X407408D01*
Y-7748D01*
D02*
G37*
G36*
X359055Y-146850D02*
X315748D01*
Y-164173D01*
X291339D01*
Y-131102D01*
X334646D01*
Y-108661D01*
X359055D01*
Y-146850D01*
D02*
G37*
G36*
X658268Y-201575D02*
X660236D01*
Y-214173D01*
X636221D01*
Y-154331D01*
X658268D01*
Y-201575D01*
D02*
G37*
G36*
X612992Y-117374D02*
X612965Y-117401D01*
X612721Y-117989D01*
Y-118625D01*
X612965Y-119213D01*
X612992Y-119241D01*
Y-121653D01*
X615748D01*
Y-160630D01*
X604331D01*
Y-201575D01*
X622441D01*
Y-231890D01*
X637810D01*
X637871Y-231915D01*
X638507D01*
X638568Y-231890D01*
X641353D01*
X641414Y-231915D01*
X642051D01*
X642111Y-231890D01*
X645290D01*
X645351Y-231915D01*
X645988D01*
X646048Y-231890D01*
X655905D01*
Y-253543D01*
X634252D01*
Y-239764D01*
X608268D01*
Y-217717D01*
X585039D01*
Y-150000D01*
X601968D01*
Y-143898D01*
X600787D01*
Y-82284D01*
X569685D01*
Y-64961D01*
X612992D01*
Y-117374D01*
D02*
G37*
%LPC*%
G36*
X362969Y-12181D02*
X360968D01*
Y-12235D01*
X360157D01*
Y-12289D01*
X359671D01*
Y-12343D01*
X359238D01*
Y-12397D01*
X358806D01*
Y-12451D01*
X358481D01*
Y-12505D01*
X358157D01*
Y-12559D01*
X357887D01*
Y-12613D01*
X357616D01*
Y-12667D01*
X357346D01*
Y-12721D01*
X357130D01*
Y-12775D01*
X356914D01*
Y-12829D01*
X356697D01*
Y-12883D01*
X356481D01*
Y-12937D01*
X356319D01*
Y-12992D01*
X356103D01*
Y-13046D01*
X355941D01*
Y-13100D01*
X355778D01*
Y-13154D01*
X355562D01*
Y-13208D01*
X355400D01*
Y-13262D01*
X355238D01*
Y-13316D01*
X355130D01*
Y-13370D01*
X354967D01*
Y-13424D01*
X354805D01*
Y-13478D01*
X354643D01*
Y-13532D01*
X354535D01*
Y-13586D01*
X354373D01*
Y-13640D01*
X354211D01*
Y-13694D01*
X354102D01*
Y-13748D01*
X353940D01*
Y-13803D01*
X353832D01*
Y-13857D01*
X353724D01*
Y-13911D01*
X353562D01*
Y-13965D01*
X353454D01*
Y-14019D01*
X353346D01*
Y-14073D01*
X353237D01*
Y-14127D01*
X353129D01*
Y-14181D01*
X352967D01*
Y-14235D01*
X352859D01*
Y-14289D01*
X352805D01*
Y-14343D01*
X352697D01*
Y-14397D01*
X352535D01*
Y-14451D01*
X352427D01*
Y-14505D01*
X352372D01*
Y-14559D01*
X352210D01*
Y-14614D01*
X352156D01*
Y-14668D01*
X352048D01*
Y-14722D01*
X351940D01*
Y-14776D01*
X351832D01*
Y-14830D01*
X351724D01*
Y-14884D01*
X351670D01*
Y-14938D01*
X351561D01*
Y-14992D01*
X351453D01*
Y-15046D01*
X351345D01*
Y-15100D01*
X351291D01*
Y-15154D01*
X351183D01*
Y-15208D01*
X351075D01*
Y-15262D01*
X351021D01*
Y-15316D01*
X350913D01*
Y-15370D01*
X350859D01*
Y-15424D01*
X350751D01*
Y-15478D01*
X350642D01*
Y-15532D01*
X350588D01*
Y-15587D01*
X350480D01*
Y-15641D01*
X350426D01*
Y-15695D01*
X350318D01*
Y-15749D01*
X350264D01*
Y-15803D01*
X350156D01*
Y-15857D01*
X350102D01*
Y-15911D01*
X349994D01*
Y-15965D01*
X349940D01*
Y-16019D01*
X349886D01*
Y-16073D01*
X349778D01*
Y-16127D01*
X349723D01*
Y-16181D01*
X349669D01*
Y-16235D01*
X349561D01*
Y-16289D01*
X349507D01*
Y-16343D01*
X349399D01*
Y-16398D01*
X349345D01*
Y-16452D01*
X349291D01*
Y-16506D01*
X349237D01*
Y-16560D01*
X349129D01*
Y-16614D01*
X349075D01*
Y-16668D01*
X349021D01*
Y-16722D01*
X348913D01*
Y-16776D01*
X348858D01*
Y-16830D01*
X348804D01*
Y-16884D01*
X348750D01*
Y-16938D01*
X348696D01*
Y-16992D01*
X348588D01*
Y-17046D01*
X348534D01*
Y-17100D01*
X348480D01*
Y-17154D01*
X348426D01*
Y-17208D01*
X348372D01*
Y-17263D01*
X348264D01*
Y-17317D01*
X348210D01*
Y-17371D01*
X348156D01*
Y-17425D01*
X348101D01*
Y-17479D01*
X348047D01*
Y-17533D01*
X347993D01*
Y-17587D01*
X347939D01*
Y-17641D01*
X347885D01*
Y-17695D01*
X347831D01*
Y-17749D01*
X347723D01*
Y-17803D01*
X347669D01*
Y-17857D01*
X347615D01*
Y-17911D01*
X347561D01*
Y-17965D01*
X347507D01*
Y-18019D01*
X347453D01*
Y-18073D01*
X347399D01*
Y-18127D01*
X347345D01*
Y-18181D01*
X347291D01*
Y-18236D01*
X347236D01*
Y-18290D01*
X347182D01*
Y-18344D01*
X347128D01*
Y-18398D01*
X347074D01*
Y-18452D01*
X347020D01*
Y-18506D01*
X346966D01*
Y-18560D01*
X346912D01*
Y-18614D01*
X346858D01*
Y-18668D01*
X346804D01*
Y-18722D01*
X346750D01*
Y-18776D01*
X346696D01*
Y-18830D01*
X346642D01*
Y-18884D01*
X346588D01*
Y-18938D01*
Y-18993D01*
X346534D01*
Y-19047D01*
X346480D01*
Y-19101D01*
X346426D01*
Y-19155D01*
X346372D01*
Y-19209D01*
X346318D01*
Y-19263D01*
X346263D01*
Y-19317D01*
X346209D01*
Y-19371D01*
X346155D01*
Y-19425D01*
Y-19479D01*
X346101D01*
Y-19533D01*
X346047D01*
Y-19587D01*
X345993D01*
Y-19641D01*
X345939D01*
Y-19695D01*
X345885D01*
Y-19749D01*
Y-19803D01*
X345831D01*
Y-19858D01*
X345777D01*
Y-19911D01*
X345723D01*
Y-19966D01*
X345669D01*
Y-20020D01*
X345615D01*
Y-20074D01*
Y-20128D01*
X345561D01*
Y-20182D01*
X345507D01*
Y-20236D01*
X345452D01*
Y-20290D01*
Y-20344D01*
X345398D01*
Y-20398D01*
X345344D01*
Y-20452D01*
X345290D01*
Y-20506D01*
X345236D01*
Y-20560D01*
Y-20614D01*
X345182D01*
Y-20668D01*
X345128D01*
Y-20722D01*
X345074D01*
Y-20776D01*
Y-20831D01*
X345020D01*
Y-20885D01*
X344966D01*
Y-20939D01*
Y-20993D01*
X344912D01*
Y-21047D01*
X344858D01*
Y-21101D01*
X344804D01*
Y-21155D01*
Y-21209D01*
X344750D01*
Y-21263D01*
X344696D01*
Y-21317D01*
Y-21371D01*
X344642D01*
Y-21425D01*
X344587D01*
Y-21479D01*
Y-21533D01*
X344533D01*
Y-21587D01*
X344479D01*
Y-21642D01*
Y-21696D01*
X344425D01*
Y-21750D01*
X344371D01*
Y-21804D01*
Y-21858D01*
X344317D01*
Y-21912D01*
X344263D01*
Y-21966D01*
Y-22020D01*
X344209D01*
Y-22074D01*
Y-22128D01*
X344155D01*
Y-22182D01*
X344101D01*
Y-22236D01*
Y-22290D01*
X344047D01*
Y-22344D01*
Y-22398D01*
X343993D01*
Y-22452D01*
X343939D01*
Y-22506D01*
Y-22561D01*
X343885D01*
Y-22615D01*
Y-22669D01*
X343831D01*
Y-22723D01*
X343777D01*
Y-22777D01*
Y-22831D01*
X343723D01*
Y-22885D01*
Y-22939D01*
X343669D01*
Y-22993D01*
Y-23047D01*
X343614D01*
Y-23101D01*
Y-23155D01*
X343560D01*
Y-23209D01*
X343506D01*
Y-23263D01*
Y-23317D01*
X343452D01*
Y-23371D01*
Y-23426D01*
X343398D01*
Y-23480D01*
Y-23534D01*
X343344D01*
Y-23588D01*
Y-23642D01*
X343290D01*
Y-23696D01*
Y-23750D01*
X343236D01*
Y-23804D01*
Y-23858D01*
X343182D01*
Y-23912D01*
Y-23966D01*
X343128D01*
Y-24020D01*
Y-24074D01*
X343074D01*
Y-24128D01*
Y-24182D01*
X343020D01*
Y-24237D01*
Y-24291D01*
Y-24345D01*
X342966D01*
Y-24399D01*
Y-24453D01*
X342912D01*
Y-24507D01*
Y-24561D01*
X342858D01*
Y-24615D01*
Y-24669D01*
X342804D01*
Y-24723D01*
Y-24777D01*
Y-24831D01*
X342749D01*
Y-24885D01*
Y-24939D01*
X342695D01*
Y-24993D01*
Y-25047D01*
X342641D01*
Y-25102D01*
Y-25155D01*
Y-25210D01*
X342587D01*
Y-25264D01*
Y-25318D01*
X342533D01*
Y-25372D01*
Y-25426D01*
Y-25480D01*
X342479D01*
Y-25534D01*
Y-25588D01*
X342425D01*
Y-25642D01*
Y-25696D01*
Y-25750D01*
X342371D01*
Y-25804D01*
Y-25858D01*
Y-25912D01*
X342317D01*
Y-25967D01*
Y-26021D01*
X342263D01*
Y-26075D01*
Y-26129D01*
Y-26183D01*
X342209D01*
Y-26237D01*
Y-26291D01*
Y-26345D01*
X342155D01*
Y-26399D01*
Y-26453D01*
Y-26507D01*
X342101D01*
Y-26561D01*
Y-26615D01*
Y-26669D01*
X342047D01*
Y-26723D01*
Y-26777D01*
Y-26831D01*
X341992D01*
Y-26886D01*
Y-26940D01*
Y-26994D01*
Y-27048D01*
X341938D01*
Y-27102D01*
Y-27156D01*
Y-27210D01*
X341884D01*
Y-27264D01*
Y-27318D01*
Y-27372D01*
Y-27426D01*
X341830D01*
Y-27480D01*
Y-27534D01*
Y-27588D01*
X341776D01*
Y-27642D01*
Y-27696D01*
Y-27751D01*
Y-27805D01*
X341722D01*
Y-27859D01*
Y-27913D01*
Y-27967D01*
Y-28021D01*
X341668D01*
Y-28075D01*
Y-28129D01*
Y-28183D01*
Y-28237D01*
X341614D01*
Y-28291D01*
Y-28345D01*
Y-28399D01*
Y-28453D01*
X341560D01*
Y-28507D01*
Y-28561D01*
Y-28615D01*
Y-28670D01*
Y-28724D01*
X341506D01*
Y-28778D01*
Y-28832D01*
Y-28886D01*
Y-28940D01*
Y-28994D01*
X341452D01*
Y-29048D01*
Y-29102D01*
Y-29156D01*
Y-29210D01*
Y-29264D01*
X341398D01*
Y-29318D01*
Y-29372D01*
Y-29426D01*
Y-29480D01*
Y-29535D01*
X341344D01*
Y-29589D01*
Y-29643D01*
Y-29697D01*
Y-29751D01*
Y-29805D01*
Y-29859D01*
X341290D01*
Y-29913D01*
Y-29967D01*
Y-30021D01*
Y-30075D01*
Y-30129D01*
Y-30183D01*
Y-30237D01*
X341236D01*
Y-30291D01*
Y-30345D01*
Y-30400D01*
Y-30454D01*
Y-30508D01*
Y-30562D01*
Y-30616D01*
Y-30670D01*
X341182D01*
Y-30724D01*
Y-30778D01*
Y-30832D01*
Y-30886D01*
Y-30940D01*
Y-30994D01*
Y-31048D01*
Y-31102D01*
Y-31156D01*
Y-31211D01*
X341127D01*
Y-31265D01*
Y-31319D01*
Y-31373D01*
Y-31427D01*
Y-31481D01*
Y-31535D01*
Y-31589D01*
Y-31643D01*
Y-31697D01*
Y-31751D01*
Y-31805D01*
Y-31859D01*
Y-31913D01*
Y-31967D01*
X341073D01*
Y-32021D01*
Y-32076D01*
Y-32129D01*
X341127D01*
Y-32184D01*
X341073D01*
Y-32238D01*
Y-32292D01*
Y-32346D01*
Y-32400D01*
Y-32454D01*
Y-32508D01*
Y-32562D01*
Y-32616D01*
Y-32670D01*
Y-32724D01*
Y-32778D01*
Y-32832D01*
X341722D01*
Y-32778D01*
Y-32724D01*
Y-32670D01*
Y-32616D01*
Y-32562D01*
Y-32508D01*
Y-32454D01*
Y-32400D01*
Y-32346D01*
Y-32292D01*
Y-32238D01*
X341776D01*
Y-32184D01*
Y-32129D01*
Y-32076D01*
Y-32021D01*
Y-31967D01*
Y-31913D01*
Y-31859D01*
Y-31805D01*
Y-31751D01*
Y-31697D01*
Y-31643D01*
Y-31589D01*
Y-31535D01*
Y-31481D01*
Y-31427D01*
Y-31373D01*
Y-31319D01*
X341830D01*
Y-31265D01*
Y-31211D01*
Y-31156D01*
Y-31102D01*
Y-31048D01*
Y-30994D01*
Y-30940D01*
Y-30886D01*
Y-30832D01*
X341884D01*
Y-30778D01*
Y-30724D01*
Y-30670D01*
Y-30616D01*
Y-30562D01*
Y-30508D01*
Y-30454D01*
Y-30400D01*
Y-30345D01*
X341938D01*
Y-30291D01*
Y-30237D01*
Y-30183D01*
Y-30129D01*
Y-30075D01*
Y-30021D01*
Y-29967D01*
X341992D01*
Y-29913D01*
Y-29859D01*
Y-29805D01*
Y-29751D01*
Y-29697D01*
Y-29643D01*
X342047D01*
Y-29589D01*
Y-29535D01*
Y-29480D01*
Y-29426D01*
Y-29372D01*
X342101D01*
Y-29318D01*
Y-29264D01*
Y-29210D01*
Y-29156D01*
Y-29102D01*
Y-29048D01*
X342155D01*
Y-28994D01*
Y-28940D01*
Y-28886D01*
Y-28832D01*
X342209D01*
Y-28778D01*
Y-28724D01*
Y-28670D01*
Y-28615D01*
Y-28561D01*
X342263D01*
Y-28507D01*
Y-28453D01*
Y-28399D01*
Y-28345D01*
X342317D01*
Y-28291D01*
Y-28237D01*
Y-28183D01*
Y-28129D01*
X342371D01*
Y-28075D01*
Y-28021D01*
Y-27967D01*
Y-27913D01*
X342425D01*
Y-27859D01*
Y-27805D01*
Y-27751D01*
Y-27696D01*
X342479D01*
Y-27642D01*
Y-27588D01*
Y-27534D01*
X342533D01*
Y-27480D01*
Y-27426D01*
Y-27372D01*
Y-27318D01*
X342587D01*
Y-27264D01*
Y-27210D01*
Y-27156D01*
X342641D01*
Y-27102D01*
Y-27048D01*
Y-26994D01*
X342695D01*
Y-26940D01*
Y-26886D01*
Y-26831D01*
Y-26777D01*
X342749D01*
Y-26723D01*
Y-26669D01*
Y-26615D01*
X342804D01*
Y-26561D01*
Y-26507D01*
Y-26453D01*
X342858D01*
Y-26399D01*
Y-26345D01*
X342912D01*
Y-26291D01*
Y-26237D01*
Y-26183D01*
X342966D01*
Y-26129D01*
Y-26075D01*
Y-26021D01*
X343020D01*
Y-25967D01*
Y-25912D01*
Y-25858D01*
X343074D01*
Y-25804D01*
Y-25750D01*
X343128D01*
Y-25696D01*
Y-25642D01*
Y-25588D01*
X343182D01*
Y-25534D01*
Y-25480D01*
X343236D01*
Y-25426D01*
Y-25372D01*
Y-25318D01*
X343290D01*
Y-25264D01*
Y-25210D01*
X343344D01*
Y-25155D01*
Y-25102D01*
X343398D01*
Y-25047D01*
Y-24993D01*
Y-24939D01*
X343452D01*
Y-24885D01*
Y-24831D01*
X343506D01*
Y-24777D01*
Y-24723D01*
X343560D01*
Y-24669D01*
Y-24615D01*
X343614D01*
Y-24561D01*
Y-24507D01*
X343669D01*
Y-24453D01*
Y-24399D01*
X343723D01*
Y-24345D01*
Y-24291D01*
Y-24237D01*
X343777D01*
Y-24182D01*
Y-24128D01*
X343831D01*
Y-24074D01*
Y-24020D01*
X343885D01*
Y-23966D01*
Y-23912D01*
X343939D01*
Y-23858D01*
Y-23804D01*
X343993D01*
Y-23750D01*
X344047D01*
Y-23696D01*
Y-23642D01*
X344101D01*
Y-23588D01*
Y-23534D01*
X344155D01*
Y-23480D01*
Y-23426D01*
X344209D01*
Y-23371D01*
Y-23317D01*
X344263D01*
Y-23263D01*
Y-23209D01*
X344317D01*
Y-23155D01*
X344371D01*
Y-23101D01*
Y-23047D01*
X344425D01*
Y-22993D01*
Y-22939D01*
X344479D01*
Y-22885D01*
Y-22831D01*
X344533D01*
Y-22777D01*
X344587D01*
Y-22723D01*
Y-22669D01*
X344642D01*
Y-22615D01*
Y-22561D01*
X344696D01*
Y-22506D01*
X344750D01*
Y-22452D01*
Y-22398D01*
X344804D01*
Y-22344D01*
Y-22290D01*
X344858D01*
Y-22236D01*
X344912D01*
Y-22182D01*
Y-22128D01*
X344966D01*
Y-22074D01*
X345020D01*
Y-22020D01*
Y-21966D01*
X345074D01*
Y-21912D01*
X345128D01*
Y-21858D01*
Y-21804D01*
X345182D01*
Y-21750D01*
X345236D01*
Y-21696D01*
Y-21642D01*
X345290D01*
Y-21587D01*
X345344D01*
Y-21533D01*
Y-21479D01*
X345398D01*
Y-21425D01*
X345452D01*
Y-21371D01*
X345507D01*
Y-21317D01*
Y-21263D01*
X345561D01*
Y-21209D01*
X345615D01*
Y-21155D01*
Y-21101D01*
X345669D01*
Y-21047D01*
X345723D01*
Y-20993D01*
X345777D01*
Y-20939D01*
Y-20885D01*
X345831D01*
Y-20831D01*
X345885D01*
Y-20776D01*
X345939D01*
Y-20722D01*
Y-20668D01*
X345993D01*
Y-20614D01*
X346047D01*
Y-20560D01*
X346101D01*
Y-20506D01*
X346155D01*
Y-20452D01*
Y-20398D01*
X346209D01*
Y-20344D01*
X346263D01*
Y-20290D01*
X346318D01*
Y-20236D01*
X346372D01*
Y-20182D01*
Y-20128D01*
X346426D01*
Y-20074D01*
X346480D01*
Y-20020D01*
X346534D01*
Y-19966D01*
X346588D01*
Y-19911D01*
X346642D01*
Y-19858D01*
X346696D01*
Y-19803D01*
Y-19749D01*
X346750D01*
Y-19695D01*
X346804D01*
Y-19641D01*
X346858D01*
Y-19587D01*
X346912D01*
Y-19533D01*
X346966D01*
Y-19479D01*
X347020D01*
Y-19425D01*
X347074D01*
Y-19371D01*
X347128D01*
Y-19317D01*
X347182D01*
Y-19263D01*
Y-19209D01*
X347236D01*
Y-19155D01*
X347291D01*
Y-19101D01*
X347345D01*
Y-19047D01*
X347399D01*
Y-18993D01*
X347453D01*
Y-18938D01*
X347507D01*
Y-18884D01*
X347561D01*
Y-18830D01*
X347615D01*
Y-18776D01*
X347669D01*
Y-18722D01*
X347723D01*
Y-18668D01*
X347777D01*
Y-18614D01*
X347831D01*
Y-18560D01*
X347885D01*
Y-18506D01*
X347939D01*
Y-18452D01*
X347993D01*
Y-18398D01*
X348047D01*
Y-18344D01*
X348101D01*
Y-18290D01*
X348210D01*
Y-18236D01*
X348264D01*
Y-18181D01*
X348318D01*
Y-18127D01*
X348372D01*
Y-18073D01*
X348426D01*
Y-18019D01*
X348480D01*
Y-17965D01*
X348534D01*
Y-17911D01*
X348588D01*
Y-17857D01*
X348642D01*
Y-17803D01*
X348750D01*
Y-17749D01*
X348804D01*
Y-17695D01*
X348858D01*
Y-17641D01*
X348913D01*
Y-17587D01*
X348967D01*
Y-17533D01*
X349021D01*
Y-17479D01*
X349129D01*
Y-17425D01*
X349183D01*
Y-17371D01*
X349237D01*
Y-17317D01*
X349291D01*
Y-17263D01*
X349399D01*
Y-17208D01*
X349453D01*
Y-17154D01*
X349507D01*
Y-17100D01*
X349561D01*
Y-17046D01*
X349669D01*
Y-16992D01*
X349723D01*
Y-16938D01*
X349778D01*
Y-16884D01*
X349886D01*
Y-16830D01*
X349940D01*
Y-16776D01*
X349994D01*
Y-16722D01*
X350102D01*
Y-16668D01*
X350156D01*
Y-16614D01*
X350264D01*
Y-16560D01*
X350318D01*
Y-16506D01*
X350372D01*
Y-16452D01*
X350480D01*
Y-16398D01*
X350534D01*
Y-16343D01*
X350642D01*
Y-16289D01*
X350696D01*
Y-16235D01*
X350805D01*
Y-16181D01*
X350859D01*
Y-16127D01*
X350967D01*
Y-16073D01*
X351021D01*
Y-16019D01*
X351129D01*
Y-15965D01*
X351183D01*
Y-15911D01*
X351291D01*
Y-15857D01*
X351399D01*
Y-15803D01*
X351453D01*
Y-15749D01*
X351561D01*
Y-15695D01*
X351670D01*
Y-15641D01*
X351724D01*
Y-15587D01*
X351832D01*
Y-15532D01*
X351940D01*
Y-15478D01*
X352048D01*
Y-15424D01*
X352102D01*
Y-15370D01*
X352210D01*
Y-15316D01*
X352318D01*
Y-15262D01*
X352427D01*
Y-15208D01*
X352535D01*
Y-15154D01*
X352643D01*
Y-15100D01*
X352751D01*
Y-15046D01*
X352859D01*
Y-14992D01*
X352967D01*
Y-14938D01*
X353021D01*
Y-14884D01*
X353129D01*
Y-14830D01*
X353292D01*
Y-14776D01*
X353400D01*
Y-14722D01*
X353508D01*
Y-14668D01*
X353616D01*
Y-14614D01*
X353724D01*
Y-14559D01*
X353886D01*
Y-14505D01*
X353994D01*
Y-14451D01*
X354102D01*
Y-14397D01*
X354265D01*
Y-14343D01*
X354373D01*
Y-14289D01*
X354535D01*
Y-14235D01*
X354643D01*
Y-14181D01*
X354805D01*
Y-14127D01*
X354913D01*
Y-14073D01*
X355076D01*
Y-14019D01*
X355238D01*
Y-13965D01*
X355400D01*
Y-13911D01*
X355562D01*
Y-13857D01*
X355724D01*
Y-13803D01*
X355887D01*
Y-13748D01*
X356049D01*
Y-13694D01*
X356211D01*
Y-13640D01*
X356427D01*
Y-13586D01*
X356589D01*
Y-13532D01*
X356805D01*
Y-13478D01*
X357022D01*
Y-13424D01*
X357238D01*
Y-13370D01*
X357454D01*
Y-13316D01*
X357725D01*
Y-13262D01*
X357995D01*
Y-13208D01*
X358265D01*
Y-13154D01*
X358590D01*
Y-13100D01*
X358914D01*
Y-13046D01*
X359238D01*
Y-12992D01*
X359725D01*
Y-12937D01*
X360320D01*
Y-12883D01*
X361185D01*
Y-12829D01*
X361239D01*
Y-12883D01*
X361293D01*
Y-12829D01*
X362644D01*
Y-12883D01*
X363617D01*
Y-12937D01*
X364212D01*
Y-12992D01*
X364645D01*
Y-13046D01*
X365023D01*
Y-13100D01*
X365347D01*
Y-13154D01*
X365726D01*
Y-13208D01*
X365942D01*
Y-13262D01*
X366212D01*
Y-13316D01*
X366483D01*
Y-13370D01*
X366699D01*
Y-13424D01*
X366915D01*
Y-13478D01*
X367131D01*
Y-13532D01*
X367348D01*
Y-13586D01*
X367510D01*
Y-13640D01*
X367726D01*
Y-13694D01*
X367888D01*
Y-13748D01*
X368050D01*
Y-13803D01*
X368213D01*
Y-13857D01*
X368429D01*
Y-13911D01*
X368537D01*
Y-13965D01*
X368699D01*
Y-14019D01*
X368861D01*
Y-14073D01*
X369023D01*
Y-14127D01*
X369132D01*
Y-14181D01*
X369294D01*
Y-14235D01*
X369456D01*
Y-14289D01*
X369564D01*
Y-14343D01*
X369726D01*
Y-14397D01*
X369834D01*
Y-14451D01*
X369943D01*
Y-14505D01*
X370105D01*
Y-14559D01*
X370213D01*
Y-14614D01*
X370321D01*
Y-14668D01*
X370429D01*
Y-14722D01*
X370537D01*
Y-14776D01*
X370645D01*
Y-14830D01*
X370808D01*
Y-14884D01*
X370916D01*
Y-14938D01*
X371024D01*
Y-14992D01*
X371132D01*
Y-15046D01*
X371240D01*
Y-15100D01*
X371294D01*
Y-15154D01*
X371402D01*
Y-15208D01*
X371510D01*
Y-15262D01*
X371619D01*
Y-15316D01*
X371727D01*
Y-15370D01*
X371835D01*
Y-15424D01*
X371943D01*
Y-15478D01*
X371997D01*
Y-15532D01*
X372105D01*
Y-15587D01*
X372213D01*
Y-15641D01*
X372267D01*
Y-15695D01*
X372375D01*
Y-15749D01*
X372483D01*
Y-15803D01*
X372538D01*
Y-15857D01*
X372646D01*
Y-15911D01*
X372754D01*
Y-15965D01*
X372808D01*
Y-16019D01*
X372916D01*
Y-16073D01*
X372970D01*
Y-16127D01*
X373078D01*
Y-16181D01*
X373132D01*
Y-16235D01*
X373240D01*
Y-16289D01*
X373294D01*
Y-16343D01*
X373403D01*
Y-16398D01*
X373457D01*
Y-16452D01*
X373565D01*
Y-16506D01*
X373619D01*
Y-16560D01*
X373727D01*
Y-16614D01*
X373781D01*
Y-16668D01*
X373835D01*
Y-16722D01*
X373943D01*
Y-16776D01*
X373997D01*
Y-16830D01*
X374051D01*
Y-16884D01*
X374159D01*
Y-16938D01*
X374214D01*
Y-16992D01*
X374268D01*
Y-17046D01*
X374376D01*
Y-17100D01*
X374430D01*
Y-17154D01*
X374484D01*
Y-17208D01*
X374538D01*
Y-17263D01*
X374646D01*
Y-17317D01*
X374700D01*
Y-17371D01*
X374754D01*
Y-17425D01*
X374808D01*
Y-17479D01*
X374916D01*
Y-17533D01*
X374970D01*
Y-17587D01*
X375024D01*
Y-17641D01*
X375079D01*
Y-17695D01*
X375132D01*
Y-17749D01*
X375241D01*
Y-17803D01*
X375295D01*
Y-17857D01*
X375349D01*
Y-17911D01*
X375403D01*
Y-17965D01*
X375457D01*
Y-18019D01*
X375511D01*
Y-18073D01*
X375565D01*
Y-18127D01*
X375619D01*
Y-18181D01*
X375673D01*
Y-18236D01*
X375781D01*
Y-18290D01*
X375835D01*
Y-18344D01*
X375889D01*
Y-18398D01*
X375943D01*
Y-18452D01*
X375997D01*
Y-18506D01*
X376052D01*
Y-18560D01*
X376106D01*
Y-18614D01*
X376160D01*
Y-18668D01*
X376214D01*
Y-18722D01*
X376268D01*
Y-18776D01*
X376322D01*
Y-18830D01*
X376376D01*
Y-18884D01*
X376430D01*
Y-18938D01*
X376484D01*
Y-18993D01*
X376538D01*
Y-19047D01*
X376592D01*
Y-19101D01*
X376646D01*
Y-19155D01*
X376700D01*
Y-19209D01*
X376754D01*
Y-19263D01*
X376809D01*
Y-19317D01*
X376863D01*
Y-19371D01*
Y-19425D01*
X376917D01*
Y-19479D01*
X376971D01*
Y-19533D01*
X377025D01*
Y-19587D01*
X377079D01*
Y-19641D01*
X377133D01*
Y-19695D01*
X377187D01*
Y-19749D01*
X377241D01*
Y-19803D01*
X377295D01*
Y-19858D01*
Y-19911D01*
X377349D01*
Y-19966D01*
X377403D01*
Y-20020D01*
X378268D01*
Y-19966D01*
X378214D01*
Y-19911D01*
X378160D01*
Y-19858D01*
X378106D01*
Y-19803D01*
Y-19749D01*
X378052D01*
Y-19695D01*
X377998D01*
Y-19641D01*
X377944D01*
Y-19587D01*
X377890D01*
Y-19533D01*
X377836D01*
Y-19479D01*
Y-19425D01*
X377782D01*
Y-19371D01*
X377728D01*
Y-19317D01*
X377674D01*
Y-19263D01*
X377619D01*
Y-19209D01*
X377565D01*
Y-19155D01*
X377511D01*
Y-19101D01*
X377457D01*
Y-19047D01*
X377403D01*
Y-18993D01*
Y-18938D01*
X377349D01*
Y-18884D01*
X377295D01*
Y-18830D01*
X377241D01*
Y-18776D01*
X377187D01*
Y-18722D01*
X377133D01*
Y-18668D01*
X377079D01*
Y-18614D01*
X377025D01*
Y-18560D01*
X376971D01*
Y-18506D01*
X376917D01*
Y-18452D01*
X376863D01*
Y-18398D01*
X376809D01*
Y-18344D01*
X376754D01*
Y-18290D01*
X376700D01*
Y-18236D01*
X376646D01*
Y-18181D01*
X376592D01*
Y-18127D01*
X376538D01*
Y-18073D01*
X376484D01*
Y-18019D01*
X376430D01*
Y-17965D01*
X376376D01*
Y-17911D01*
X376322D01*
Y-17857D01*
X376268D01*
Y-17803D01*
X376214D01*
Y-17749D01*
X376160D01*
Y-17695D01*
X376106D01*
Y-17641D01*
X375997D01*
Y-17587D01*
X375943D01*
Y-17533D01*
X375889D01*
Y-17479D01*
X375835D01*
Y-17425D01*
X375781D01*
Y-17371D01*
X375727D01*
Y-17317D01*
X375673D01*
Y-17263D01*
X375619D01*
Y-17208D01*
X375511D01*
Y-17154D01*
X375457D01*
Y-17100D01*
X375403D01*
Y-17046D01*
X375349D01*
Y-16992D01*
X375295D01*
Y-16938D01*
X375187D01*
Y-16884D01*
X375132D01*
Y-16830D01*
X375079D01*
Y-16776D01*
X375024D01*
Y-16722D01*
X374916D01*
Y-16668D01*
X374862D01*
Y-16614D01*
X374808D01*
Y-16560D01*
X374754D01*
Y-16506D01*
X374646D01*
Y-16452D01*
X374592D01*
Y-16398D01*
X374538D01*
Y-16343D01*
X374430D01*
Y-16289D01*
X374376D01*
Y-16235D01*
X374322D01*
Y-16181D01*
X374214D01*
Y-16127D01*
X374159D01*
Y-16073D01*
X374051D01*
Y-16019D01*
X373997D01*
Y-15965D01*
X373943D01*
Y-15911D01*
X373835D01*
Y-15857D01*
X373781D01*
Y-15803D01*
X373673D01*
Y-15749D01*
X373619D01*
Y-15695D01*
X373511D01*
Y-15641D01*
X373457D01*
Y-15587D01*
X373348D01*
Y-15532D01*
X373294D01*
Y-15478D01*
X373186D01*
Y-15424D01*
X373132D01*
Y-15370D01*
X373024D01*
Y-15316D01*
X372916D01*
Y-15262D01*
X372862D01*
Y-15208D01*
X372754D01*
Y-15154D01*
X372646D01*
Y-15100D01*
X372592D01*
Y-15046D01*
X372483D01*
Y-14992D01*
X372375D01*
Y-14938D01*
X372321D01*
Y-14884D01*
X372213D01*
Y-14830D01*
X372105D01*
Y-14776D01*
X371997D01*
Y-14722D01*
X371889D01*
Y-14668D01*
X371835D01*
Y-14614D01*
X371727D01*
Y-14559D01*
X371619D01*
Y-14505D01*
X371510D01*
Y-14451D01*
X371402D01*
Y-14397D01*
X371294D01*
Y-14343D01*
X371186D01*
Y-14289D01*
X371078D01*
Y-14235D01*
X370970D01*
Y-14181D01*
X370862D01*
Y-14127D01*
X370700D01*
Y-14073D01*
X370591D01*
Y-14019D01*
X370483D01*
Y-13965D01*
X370375D01*
Y-13911D01*
X370213D01*
Y-13857D01*
X370105D01*
Y-13803D01*
X369997D01*
Y-13748D01*
X369834D01*
Y-13694D01*
X369726D01*
Y-13640D01*
X369564D01*
Y-13586D01*
X369456D01*
Y-13532D01*
X369294D01*
Y-13478D01*
X369132D01*
Y-13424D01*
X368969D01*
Y-13370D01*
X368861D01*
Y-13316D01*
X368699D01*
Y-13262D01*
X368537D01*
Y-13208D01*
X368375D01*
Y-13154D01*
X368159D01*
Y-13100D01*
X367996D01*
Y-13046D01*
X367834D01*
Y-12992D01*
X367618D01*
Y-12937D01*
X367456D01*
Y-12883D01*
X367239D01*
Y-12829D01*
X367023D01*
Y-12775D01*
X366807D01*
Y-12721D01*
X366591D01*
Y-12667D01*
X366320D01*
Y-12613D01*
X366050D01*
Y-12559D01*
X365780D01*
Y-12505D01*
X365456D01*
Y-12451D01*
X365077D01*
Y-12397D01*
X364753D01*
Y-12343D01*
X364320D01*
Y-12289D01*
X363779D01*
Y-12235D01*
X362969D01*
Y-12181D01*
D02*
G37*
G36*
X386972Y-20885D02*
X378647D01*
Y-20939D01*
X378592D01*
Y-20885D01*
X378484D01*
Y-20939D01*
X378376D01*
Y-20993D01*
X378322D01*
Y-21047D01*
X378268D01*
Y-21101D01*
Y-21155D01*
Y-21209D01*
X378214D01*
Y-21263D01*
Y-21317D01*
Y-21371D01*
Y-21425D01*
Y-21479D01*
Y-21533D01*
Y-21587D01*
Y-21642D01*
Y-21696D01*
Y-21750D01*
Y-21804D01*
Y-21858D01*
Y-21912D01*
Y-21966D01*
Y-22020D01*
Y-22074D01*
Y-22128D01*
Y-22182D01*
Y-22236D01*
Y-22290D01*
Y-22344D01*
Y-22398D01*
Y-22452D01*
Y-22506D01*
Y-22561D01*
Y-22615D01*
Y-22669D01*
Y-22723D01*
Y-22777D01*
Y-22831D01*
Y-22885D01*
Y-22939D01*
Y-22993D01*
Y-23047D01*
Y-23101D01*
Y-23155D01*
Y-23209D01*
Y-23263D01*
Y-23317D01*
Y-23371D01*
Y-23426D01*
Y-23480D01*
X378268D01*
Y-23534D01*
Y-23588D01*
Y-23642D01*
X378322D01*
Y-23696D01*
X378376D01*
Y-23750D01*
X378538D01*
Y-23804D01*
X381133D01*
Y-23858D01*
X381188D01*
Y-23912D01*
X381242D01*
Y-23966D01*
Y-24020D01*
Y-24074D01*
Y-24128D01*
Y-24182D01*
Y-24237D01*
Y-24291D01*
Y-24345D01*
Y-24399D01*
Y-24453D01*
Y-24507D01*
Y-24561D01*
Y-24615D01*
Y-24669D01*
Y-24723D01*
Y-24777D01*
Y-24831D01*
Y-24885D01*
Y-24939D01*
Y-24993D01*
Y-25047D01*
Y-25102D01*
Y-25155D01*
Y-25210D01*
Y-25264D01*
Y-25318D01*
Y-25372D01*
Y-25426D01*
Y-25480D01*
Y-25534D01*
Y-25588D01*
Y-25642D01*
Y-25696D01*
Y-25750D01*
Y-25804D01*
Y-25858D01*
Y-25912D01*
Y-25967D01*
Y-26021D01*
Y-26075D01*
Y-26129D01*
Y-26183D01*
Y-26237D01*
Y-26291D01*
Y-26345D01*
Y-26399D01*
Y-26453D01*
Y-26507D01*
Y-26561D01*
Y-26615D01*
Y-26669D01*
Y-26723D01*
Y-26777D01*
Y-26831D01*
Y-26886D01*
Y-26940D01*
Y-26994D01*
Y-27048D01*
Y-27102D01*
Y-27156D01*
Y-27210D01*
Y-27264D01*
Y-27318D01*
Y-27372D01*
Y-27426D01*
Y-27480D01*
Y-27534D01*
Y-27588D01*
Y-27642D01*
Y-27696D01*
Y-27751D01*
Y-27805D01*
Y-27859D01*
Y-27913D01*
Y-27967D01*
Y-28021D01*
Y-28075D01*
Y-28129D01*
Y-28183D01*
Y-28237D01*
Y-28291D01*
Y-28345D01*
Y-28399D01*
Y-28453D01*
Y-28507D01*
Y-28561D01*
Y-28615D01*
Y-28670D01*
Y-28724D01*
Y-28778D01*
Y-28832D01*
Y-28886D01*
Y-28940D01*
Y-28994D01*
Y-29048D01*
Y-29102D01*
Y-29156D01*
Y-29210D01*
Y-29264D01*
Y-29318D01*
Y-29372D01*
Y-29426D01*
Y-29480D01*
Y-29535D01*
Y-29589D01*
Y-29643D01*
Y-29697D01*
Y-29751D01*
Y-29805D01*
Y-29859D01*
Y-29913D01*
Y-29967D01*
Y-30021D01*
Y-30075D01*
Y-30129D01*
Y-30183D01*
Y-30237D01*
Y-30291D01*
Y-30345D01*
Y-30400D01*
Y-30454D01*
Y-30508D01*
Y-30562D01*
Y-30616D01*
Y-30670D01*
Y-30724D01*
Y-30778D01*
Y-30832D01*
Y-30886D01*
Y-30940D01*
Y-30994D01*
Y-31048D01*
Y-31102D01*
Y-31156D01*
Y-31211D01*
Y-31265D01*
Y-31319D01*
Y-31373D01*
Y-31427D01*
Y-31481D01*
Y-31535D01*
Y-31589D01*
Y-31643D01*
Y-31697D01*
Y-31751D01*
Y-31805D01*
Y-31859D01*
Y-31913D01*
Y-31967D01*
Y-32021D01*
Y-32076D01*
Y-32129D01*
Y-32184D01*
Y-32238D01*
Y-32292D01*
Y-32346D01*
Y-32400D01*
X381296D01*
Y-32454D01*
Y-32508D01*
Y-32562D01*
X381350D01*
Y-32616D01*
X381404D01*
Y-32670D01*
X384053D01*
Y-32616D01*
X384107D01*
Y-32562D01*
X384161D01*
Y-32508D01*
X384215D01*
Y-32454D01*
Y-32400D01*
Y-32346D01*
Y-32292D01*
Y-32238D01*
Y-32184D01*
Y-32129D01*
Y-32076D01*
Y-32021D01*
Y-31967D01*
Y-31913D01*
Y-31859D01*
Y-31805D01*
Y-31751D01*
Y-31697D01*
Y-31643D01*
Y-31589D01*
Y-31535D01*
Y-31481D01*
Y-31427D01*
Y-31373D01*
Y-31319D01*
Y-31265D01*
Y-31211D01*
Y-31156D01*
Y-31102D01*
Y-31048D01*
Y-30994D01*
Y-30940D01*
Y-30886D01*
Y-30832D01*
Y-30778D01*
Y-30724D01*
Y-30670D01*
Y-30616D01*
Y-30562D01*
Y-30508D01*
Y-30454D01*
Y-30400D01*
Y-30345D01*
Y-30291D01*
Y-30237D01*
Y-30183D01*
Y-30129D01*
Y-30075D01*
Y-30021D01*
Y-29967D01*
Y-29913D01*
Y-29859D01*
Y-29805D01*
Y-29751D01*
Y-29697D01*
Y-29643D01*
Y-29589D01*
Y-29535D01*
Y-29480D01*
Y-29426D01*
Y-29372D01*
Y-29318D01*
Y-29264D01*
Y-29210D01*
Y-29156D01*
Y-29102D01*
Y-29048D01*
Y-28994D01*
Y-28940D01*
Y-28886D01*
Y-28832D01*
Y-28778D01*
Y-28724D01*
Y-28670D01*
Y-28615D01*
Y-28561D01*
Y-28507D01*
Y-28453D01*
Y-28399D01*
Y-28345D01*
Y-28291D01*
Y-28237D01*
Y-28183D01*
Y-28129D01*
Y-28075D01*
Y-28021D01*
Y-27967D01*
Y-27913D01*
Y-27859D01*
Y-27805D01*
Y-27751D01*
Y-27696D01*
Y-27642D01*
Y-27588D01*
Y-27534D01*
Y-27480D01*
Y-27426D01*
Y-27372D01*
Y-27318D01*
Y-27264D01*
Y-27210D01*
Y-27156D01*
Y-27102D01*
Y-27048D01*
Y-26994D01*
Y-26940D01*
Y-26886D01*
Y-26831D01*
Y-26777D01*
Y-26723D01*
Y-26669D01*
Y-26615D01*
Y-26561D01*
Y-26507D01*
Y-26453D01*
Y-26399D01*
Y-26345D01*
Y-26291D01*
Y-26237D01*
Y-26183D01*
Y-26129D01*
Y-26075D01*
Y-26021D01*
Y-25967D01*
Y-25912D01*
Y-25858D01*
Y-25804D01*
Y-25750D01*
Y-25696D01*
Y-25642D01*
Y-25588D01*
Y-25534D01*
Y-25480D01*
Y-25426D01*
Y-25372D01*
Y-25318D01*
Y-25264D01*
Y-25210D01*
Y-25155D01*
Y-25102D01*
Y-25047D01*
Y-24993D01*
Y-24939D01*
Y-24885D01*
Y-24831D01*
Y-24777D01*
Y-24723D01*
Y-24669D01*
Y-24615D01*
Y-24561D01*
Y-24507D01*
Y-24453D01*
Y-24399D01*
Y-24345D01*
Y-24291D01*
Y-24237D01*
Y-24182D01*
Y-24128D01*
Y-24074D01*
Y-24020D01*
X384269D01*
Y-23966D01*
Y-23912D01*
X384323D01*
Y-23858D01*
X384377D01*
Y-23804D01*
X386972D01*
Y-23750D01*
X387080D01*
Y-23696D01*
X387134D01*
Y-23642D01*
X387188D01*
Y-23588D01*
X387242D01*
Y-23534D01*
Y-23480D01*
Y-23426D01*
Y-23371D01*
Y-23317D01*
Y-23263D01*
Y-23209D01*
Y-23155D01*
Y-23101D01*
Y-23047D01*
Y-22993D01*
Y-22939D01*
Y-22885D01*
Y-22831D01*
Y-22777D01*
Y-22723D01*
Y-22669D01*
Y-22615D01*
Y-22561D01*
Y-22506D01*
Y-22452D01*
Y-22398D01*
Y-22344D01*
Y-22290D01*
Y-22236D01*
Y-22182D01*
Y-22128D01*
Y-22074D01*
Y-22020D01*
Y-21966D01*
Y-21912D01*
Y-21858D01*
Y-21804D01*
Y-21750D01*
Y-21696D01*
Y-21642D01*
Y-21587D01*
Y-21533D01*
Y-21479D01*
Y-21425D01*
Y-21371D01*
Y-21317D01*
Y-21263D01*
Y-21209D01*
Y-21155D01*
Y-21101D01*
X387188D01*
Y-21047D01*
Y-20993D01*
X387134D01*
Y-20939D01*
X386972D01*
Y-20885D01*
D02*
G37*
G36*
X357346D02*
X351021D01*
Y-20939D01*
X350967D01*
Y-20885D01*
X350805D01*
Y-20939D01*
X350696D01*
Y-20993D01*
X350642D01*
Y-21047D01*
X350588D01*
Y-21101D01*
Y-21155D01*
X350534D01*
Y-21209D01*
Y-21263D01*
Y-21317D01*
Y-21371D01*
Y-21425D01*
Y-21479D01*
Y-21533D01*
Y-21587D01*
Y-21642D01*
Y-21696D01*
Y-21750D01*
Y-21804D01*
Y-21858D01*
Y-21912D01*
Y-21966D01*
Y-22020D01*
Y-22074D01*
Y-22128D01*
Y-22182D01*
Y-22236D01*
Y-22290D01*
Y-22344D01*
Y-22398D01*
Y-22452D01*
Y-22506D01*
Y-22561D01*
Y-22615D01*
Y-22669D01*
Y-22723D01*
Y-22777D01*
Y-22831D01*
Y-22885D01*
Y-22939D01*
Y-22993D01*
Y-23047D01*
Y-23101D01*
Y-23155D01*
Y-23209D01*
Y-23263D01*
Y-23317D01*
Y-23371D01*
Y-23426D01*
Y-23480D01*
X350588D01*
Y-23534D01*
X350642D01*
Y-23588D01*
X350696D01*
Y-23642D01*
X356535D01*
Y-23696D01*
X356589D01*
Y-23750D01*
Y-23804D01*
Y-23858D01*
Y-23912D01*
Y-23966D01*
Y-24020D01*
Y-24074D01*
Y-24128D01*
Y-24182D01*
Y-24237D01*
Y-24291D01*
Y-24345D01*
Y-24399D01*
Y-24453D01*
Y-24507D01*
Y-24561D01*
Y-24615D01*
Y-24669D01*
Y-24723D01*
Y-24777D01*
Y-24831D01*
Y-24885D01*
Y-24939D01*
Y-24993D01*
Y-25047D01*
Y-25102D01*
Y-25155D01*
Y-25210D01*
Y-25264D01*
Y-25318D01*
Y-25372D01*
Y-25426D01*
Y-25480D01*
Y-25534D01*
Y-25588D01*
X356535D01*
Y-25642D01*
X351561D01*
Y-25696D01*
X351453D01*
Y-25750D01*
Y-25804D01*
X351399D01*
Y-25858D01*
Y-25912D01*
Y-25967D01*
Y-26021D01*
Y-26075D01*
Y-26129D01*
Y-26183D01*
Y-26237D01*
Y-26291D01*
Y-26345D01*
Y-26399D01*
Y-26453D01*
Y-26507D01*
Y-26561D01*
Y-26615D01*
Y-26669D01*
Y-26723D01*
Y-26777D01*
Y-26831D01*
Y-26886D01*
Y-26940D01*
Y-26994D01*
Y-27048D01*
Y-27102D01*
Y-27156D01*
Y-27210D01*
Y-27264D01*
Y-27318D01*
Y-27372D01*
Y-27426D01*
Y-27480D01*
Y-27534D01*
Y-27588D01*
Y-27642D01*
Y-27696D01*
Y-27751D01*
Y-27805D01*
X351453D01*
Y-27859D01*
Y-27913D01*
X351561D01*
Y-27967D01*
X356535D01*
Y-28021D01*
X356589D01*
Y-28075D01*
Y-28129D01*
Y-28183D01*
Y-28237D01*
Y-28291D01*
Y-28345D01*
Y-28399D01*
Y-28453D01*
Y-28507D01*
Y-28561D01*
Y-28615D01*
Y-28670D01*
Y-28724D01*
Y-28778D01*
Y-28832D01*
Y-28886D01*
Y-28940D01*
Y-28994D01*
Y-29048D01*
Y-29102D01*
Y-29156D01*
Y-29210D01*
Y-29264D01*
Y-29318D01*
Y-29372D01*
Y-29426D01*
Y-29480D01*
Y-29535D01*
Y-29589D01*
Y-29643D01*
Y-29697D01*
Y-29751D01*
Y-29805D01*
Y-29859D01*
X356535D01*
Y-29913D01*
X350751D01*
Y-29967D01*
X350642D01*
Y-30021D01*
X350588D01*
Y-30075D01*
Y-30129D01*
X350534D01*
Y-30183D01*
Y-30237D01*
Y-30291D01*
Y-30345D01*
Y-30400D01*
Y-30454D01*
Y-30508D01*
Y-30562D01*
Y-30616D01*
Y-30670D01*
Y-30724D01*
Y-30778D01*
Y-30832D01*
Y-30886D01*
Y-30940D01*
Y-30994D01*
Y-31048D01*
Y-31102D01*
Y-31156D01*
Y-31211D01*
Y-31265D01*
Y-31319D01*
Y-31373D01*
Y-31427D01*
Y-31481D01*
Y-31535D01*
Y-31589D01*
Y-31643D01*
Y-31697D01*
Y-31751D01*
Y-31805D01*
Y-31859D01*
Y-31913D01*
Y-31967D01*
Y-32021D01*
Y-32076D01*
Y-32129D01*
Y-32184D01*
Y-32238D01*
Y-32292D01*
Y-32346D01*
Y-32400D01*
Y-32454D01*
X350588D01*
Y-32508D01*
Y-32562D01*
X350642D01*
Y-32616D01*
X350696D01*
Y-32670D01*
X357562D01*
Y-32616D01*
X357779D01*
Y-32562D01*
X357887D01*
Y-32508D01*
X357941D01*
Y-32454D01*
X357995D01*
Y-32400D01*
X358049D01*
Y-32346D01*
X358103D01*
Y-32292D01*
X358157D01*
Y-32238D01*
X358211D01*
Y-32184D01*
X358265D01*
Y-32129D01*
X358319D01*
Y-32076D01*
X358373D01*
Y-32021D01*
X358427D01*
Y-31967D01*
X358481D01*
Y-31913D01*
X358536D01*
Y-31859D01*
X358590D01*
Y-31805D01*
X358644D01*
Y-31751D01*
X358698D01*
Y-31697D01*
X358752D01*
Y-31643D01*
X358806D01*
Y-31589D01*
X358860D01*
Y-31535D01*
X358914D01*
Y-31481D01*
X358968D01*
Y-31427D01*
X359022D01*
Y-31373D01*
X359076D01*
Y-31319D01*
X359130D01*
Y-31265D01*
X359184D01*
Y-31211D01*
X359238D01*
Y-31156D01*
X359292D01*
Y-31102D01*
X359346D01*
Y-31048D01*
X359401D01*
Y-30994D01*
Y-30940D01*
X359455D01*
Y-30886D01*
Y-30832D01*
X359509D01*
Y-30778D01*
Y-30724D01*
Y-30670D01*
Y-30616D01*
Y-30562D01*
X359563D01*
Y-30508D01*
Y-30454D01*
Y-30400D01*
Y-30345D01*
Y-30291D01*
Y-30237D01*
Y-30183D01*
Y-30129D01*
Y-30075D01*
Y-30021D01*
Y-29967D01*
Y-29913D01*
Y-29859D01*
Y-29805D01*
Y-29751D01*
Y-29697D01*
Y-29643D01*
Y-29589D01*
Y-29535D01*
Y-29480D01*
Y-29426D01*
Y-29372D01*
Y-29318D01*
Y-29264D01*
Y-29210D01*
Y-29156D01*
Y-29102D01*
Y-29048D01*
Y-28994D01*
Y-28940D01*
Y-28886D01*
Y-28832D01*
Y-28778D01*
Y-28724D01*
Y-28670D01*
Y-28615D01*
Y-28561D01*
Y-28507D01*
Y-28453D01*
Y-28399D01*
Y-28345D01*
Y-28291D01*
Y-28237D01*
Y-28183D01*
Y-28129D01*
Y-28075D01*
Y-28021D01*
Y-27967D01*
Y-27913D01*
Y-27859D01*
Y-27805D01*
Y-27751D01*
Y-27696D01*
Y-27642D01*
Y-27588D01*
Y-27534D01*
Y-27480D01*
Y-27426D01*
Y-27372D01*
Y-27318D01*
Y-27264D01*
Y-27210D01*
Y-27156D01*
Y-27102D01*
Y-27048D01*
Y-26994D01*
Y-26940D01*
Y-26886D01*
Y-26831D01*
Y-26777D01*
Y-26723D01*
Y-26669D01*
Y-26615D01*
Y-26561D01*
Y-26507D01*
Y-26453D01*
Y-26399D01*
Y-26345D01*
Y-26291D01*
Y-26237D01*
Y-26183D01*
Y-26129D01*
Y-26075D01*
Y-26021D01*
Y-25967D01*
Y-25912D01*
Y-25858D01*
Y-25804D01*
Y-25750D01*
Y-25696D01*
Y-25642D01*
Y-25588D01*
Y-25534D01*
Y-25480D01*
Y-25426D01*
Y-25372D01*
Y-25318D01*
Y-25264D01*
Y-25210D01*
Y-25155D01*
Y-25102D01*
Y-25047D01*
Y-24993D01*
Y-24939D01*
Y-24885D01*
Y-24831D01*
Y-24777D01*
Y-24723D01*
Y-24669D01*
Y-24615D01*
Y-24561D01*
Y-24507D01*
Y-24453D01*
Y-24399D01*
Y-24345D01*
Y-24291D01*
Y-24237D01*
Y-24182D01*
Y-24128D01*
Y-24074D01*
Y-24020D01*
Y-23966D01*
Y-23912D01*
Y-23858D01*
Y-23804D01*
Y-23750D01*
Y-23696D01*
Y-23642D01*
Y-23588D01*
Y-23534D01*
Y-23480D01*
Y-23426D01*
Y-23371D01*
Y-23317D01*
Y-23263D01*
Y-23209D01*
Y-23155D01*
Y-23101D01*
Y-23047D01*
X359509D01*
Y-22993D01*
Y-22939D01*
Y-22885D01*
Y-22831D01*
Y-22777D01*
X359455D01*
Y-22723D01*
Y-22669D01*
Y-22615D01*
X359401D01*
Y-22561D01*
X359346D01*
Y-22506D01*
X359292D01*
Y-22452D01*
X359238D01*
Y-22398D01*
X359184D01*
Y-22344D01*
X359130D01*
Y-22290D01*
X359076D01*
Y-22236D01*
X359022D01*
Y-22182D01*
X358968D01*
Y-22128D01*
X358914D01*
Y-22074D01*
X358860D01*
Y-22020D01*
X358806D01*
Y-21966D01*
X358752D01*
Y-21912D01*
X358698D01*
Y-21858D01*
X358644D01*
Y-21804D01*
X358590D01*
Y-21750D01*
X358536D01*
Y-21696D01*
X358481D01*
Y-21642D01*
X358427D01*
Y-21587D01*
X358373D01*
Y-21533D01*
X358319D01*
Y-21479D01*
X358265D01*
Y-21425D01*
X358211D01*
Y-21371D01*
X358157D01*
Y-21317D01*
X358103D01*
Y-21263D01*
X358049D01*
Y-21209D01*
X357995D01*
Y-21155D01*
X357941D01*
Y-21101D01*
X357887D01*
Y-21047D01*
X357779D01*
Y-20993D01*
X357616D01*
Y-20939D01*
X357346D01*
Y-20885D01*
D02*
G37*
G36*
X377295D02*
X374808D01*
Y-20939D01*
X374700D01*
Y-20993D01*
X374646D01*
Y-21047D01*
X374592D01*
Y-21101D01*
Y-21155D01*
Y-21209D01*
Y-21263D01*
Y-21317D01*
Y-21371D01*
Y-21425D01*
Y-21479D01*
Y-21533D01*
Y-21587D01*
Y-21642D01*
Y-21696D01*
Y-21750D01*
Y-21804D01*
Y-21858D01*
Y-21912D01*
Y-21966D01*
Y-22020D01*
Y-22074D01*
Y-22128D01*
Y-22182D01*
Y-22236D01*
Y-22290D01*
Y-22344D01*
Y-22398D01*
Y-22452D01*
Y-22506D01*
Y-22561D01*
Y-22615D01*
Y-22669D01*
Y-22723D01*
Y-22777D01*
Y-22831D01*
Y-22885D01*
Y-22939D01*
Y-22993D01*
Y-23047D01*
Y-23101D01*
Y-23155D01*
Y-23209D01*
Y-23263D01*
Y-23317D01*
Y-23371D01*
Y-23426D01*
Y-23480D01*
Y-23534D01*
Y-23588D01*
Y-23642D01*
Y-23696D01*
Y-23750D01*
Y-23804D01*
Y-23858D01*
Y-23912D01*
Y-23966D01*
Y-24020D01*
Y-24074D01*
Y-24128D01*
Y-24182D01*
Y-24237D01*
Y-24291D01*
Y-24345D01*
Y-24399D01*
Y-24453D01*
Y-24507D01*
Y-24561D01*
Y-24615D01*
Y-24669D01*
Y-24723D01*
Y-24777D01*
Y-24831D01*
Y-24885D01*
Y-24939D01*
Y-24993D01*
Y-25047D01*
Y-25102D01*
Y-25155D01*
Y-25210D01*
Y-25264D01*
Y-25318D01*
Y-25372D01*
Y-25426D01*
Y-25480D01*
Y-25534D01*
Y-25588D01*
Y-25642D01*
Y-25696D01*
Y-25750D01*
Y-25804D01*
Y-25858D01*
Y-25912D01*
Y-25967D01*
Y-26021D01*
Y-26075D01*
Y-26129D01*
Y-26183D01*
Y-26237D01*
Y-26291D01*
Y-26345D01*
Y-26399D01*
Y-26453D01*
Y-26507D01*
Y-26561D01*
Y-26615D01*
Y-26669D01*
Y-26723D01*
Y-26777D01*
Y-26831D01*
Y-26886D01*
Y-26940D01*
Y-26994D01*
Y-27048D01*
Y-27102D01*
Y-27156D01*
Y-27210D01*
Y-27264D01*
Y-27318D01*
Y-27372D01*
Y-27426D01*
Y-27480D01*
Y-27534D01*
Y-27588D01*
Y-27642D01*
Y-27696D01*
Y-27751D01*
Y-27805D01*
Y-27859D01*
Y-27913D01*
Y-27967D01*
Y-28021D01*
Y-28075D01*
Y-28129D01*
Y-28183D01*
Y-28237D01*
Y-28291D01*
Y-28345D01*
Y-28399D01*
Y-28453D01*
Y-28507D01*
Y-28561D01*
Y-28615D01*
Y-28670D01*
Y-28724D01*
Y-28778D01*
Y-28832D01*
Y-28886D01*
Y-28940D01*
Y-28994D01*
Y-29048D01*
Y-29102D01*
Y-29156D01*
Y-29210D01*
Y-29264D01*
Y-29318D01*
Y-29372D01*
Y-29426D01*
Y-29480D01*
Y-29535D01*
Y-29589D01*
Y-29643D01*
Y-29697D01*
Y-29751D01*
Y-29805D01*
Y-29859D01*
Y-29913D01*
Y-29967D01*
Y-30021D01*
Y-30075D01*
Y-30129D01*
Y-30183D01*
Y-30237D01*
Y-30291D01*
Y-30345D01*
Y-30400D01*
Y-30454D01*
Y-30508D01*
Y-30562D01*
Y-30616D01*
Y-30670D01*
Y-30724D01*
Y-30778D01*
Y-30832D01*
Y-30886D01*
Y-30940D01*
Y-30994D01*
Y-31048D01*
Y-31102D01*
Y-31156D01*
Y-31211D01*
Y-31265D01*
Y-31319D01*
Y-31373D01*
Y-31427D01*
Y-31481D01*
Y-31535D01*
Y-31589D01*
Y-31643D01*
Y-31697D01*
Y-31751D01*
Y-31805D01*
Y-31859D01*
Y-31913D01*
Y-31967D01*
Y-32021D01*
Y-32076D01*
Y-32129D01*
Y-32184D01*
Y-32238D01*
Y-32292D01*
Y-32346D01*
Y-32400D01*
Y-32454D01*
Y-32508D01*
Y-32562D01*
X374646D01*
Y-32616D01*
X374700D01*
Y-32670D01*
X377403D01*
Y-32616D01*
X377457D01*
Y-32562D01*
X377511D01*
Y-32508D01*
Y-32454D01*
X377565D01*
Y-32400D01*
Y-32346D01*
Y-32292D01*
Y-32238D01*
Y-32184D01*
Y-32129D01*
Y-32076D01*
Y-32021D01*
Y-31967D01*
Y-31913D01*
Y-31859D01*
Y-31805D01*
Y-31751D01*
Y-31697D01*
Y-31643D01*
Y-31589D01*
Y-31535D01*
Y-31481D01*
Y-31427D01*
Y-31373D01*
Y-31319D01*
Y-31265D01*
Y-31211D01*
Y-31156D01*
Y-31102D01*
Y-31048D01*
Y-30994D01*
Y-30940D01*
Y-30886D01*
Y-30832D01*
Y-30778D01*
Y-30724D01*
Y-30670D01*
Y-30616D01*
Y-30562D01*
Y-30508D01*
Y-30454D01*
Y-30400D01*
Y-30345D01*
Y-30291D01*
Y-30237D01*
Y-30183D01*
Y-30129D01*
Y-30075D01*
Y-30021D01*
Y-29967D01*
Y-29913D01*
Y-29859D01*
Y-29805D01*
Y-29751D01*
Y-29697D01*
Y-29643D01*
Y-29589D01*
Y-29535D01*
Y-29480D01*
Y-29426D01*
Y-29372D01*
Y-29318D01*
Y-29264D01*
Y-29210D01*
Y-29156D01*
Y-29102D01*
Y-29048D01*
Y-28994D01*
Y-28940D01*
Y-28886D01*
Y-28832D01*
Y-28778D01*
Y-28724D01*
Y-28670D01*
Y-28615D01*
Y-28561D01*
Y-28507D01*
Y-28453D01*
Y-28399D01*
Y-28345D01*
Y-28291D01*
Y-28237D01*
Y-28183D01*
Y-28129D01*
Y-28075D01*
Y-28021D01*
Y-27967D01*
Y-27913D01*
Y-27859D01*
Y-27805D01*
Y-27751D01*
Y-27696D01*
Y-27642D01*
Y-27588D01*
Y-27534D01*
Y-27480D01*
Y-27426D01*
Y-27372D01*
Y-27318D01*
Y-27264D01*
Y-27210D01*
Y-27156D01*
Y-27102D01*
Y-27048D01*
Y-26994D01*
Y-26940D01*
Y-26886D01*
Y-26831D01*
Y-26777D01*
Y-26723D01*
Y-26669D01*
Y-26615D01*
Y-26561D01*
Y-26507D01*
Y-26453D01*
Y-26399D01*
Y-26345D01*
Y-26291D01*
Y-26237D01*
Y-26183D01*
Y-26129D01*
Y-26075D01*
Y-26021D01*
Y-25967D01*
Y-25912D01*
Y-25858D01*
Y-25804D01*
Y-25750D01*
Y-25696D01*
Y-25642D01*
Y-25588D01*
Y-25534D01*
Y-25480D01*
Y-25426D01*
Y-25372D01*
Y-25318D01*
Y-25264D01*
Y-25210D01*
Y-25155D01*
Y-25102D01*
Y-25047D01*
Y-24993D01*
Y-24939D01*
Y-24885D01*
Y-24831D01*
Y-24777D01*
Y-24723D01*
Y-24669D01*
Y-24615D01*
Y-24561D01*
Y-24507D01*
Y-24453D01*
Y-24399D01*
Y-24345D01*
Y-24291D01*
Y-24237D01*
Y-24182D01*
Y-24128D01*
Y-24074D01*
Y-24020D01*
Y-23966D01*
Y-23912D01*
Y-23858D01*
Y-23804D01*
Y-23750D01*
Y-23696D01*
Y-23642D01*
Y-23588D01*
Y-23534D01*
Y-23480D01*
Y-23426D01*
Y-23371D01*
Y-23317D01*
Y-23263D01*
Y-23209D01*
Y-23155D01*
Y-23101D01*
Y-23047D01*
Y-22993D01*
Y-22939D01*
Y-22885D01*
Y-22831D01*
Y-22777D01*
Y-22723D01*
Y-22669D01*
Y-22615D01*
Y-22561D01*
Y-22506D01*
Y-22452D01*
Y-22398D01*
Y-22344D01*
Y-22290D01*
Y-22236D01*
Y-22182D01*
Y-22128D01*
Y-22074D01*
Y-22020D01*
Y-21966D01*
Y-21912D01*
Y-21858D01*
Y-21804D01*
Y-21750D01*
Y-21696D01*
Y-21642D01*
Y-21587D01*
Y-21533D01*
Y-21479D01*
Y-21425D01*
Y-21371D01*
Y-21317D01*
Y-21263D01*
Y-21209D01*
Y-21155D01*
X377511D01*
Y-21101D01*
Y-21047D01*
X377457D01*
Y-20993D01*
Y-20939D01*
X377295D01*
Y-20885D01*
D02*
G37*
G36*
X372970D02*
X364699D01*
Y-20939D01*
Y-20993D01*
Y-21047D01*
Y-21101D01*
Y-21155D01*
Y-21209D01*
Y-21263D01*
Y-21317D01*
Y-21371D01*
Y-21425D01*
Y-21479D01*
Y-21533D01*
Y-21587D01*
Y-21642D01*
Y-21696D01*
Y-21750D01*
Y-21804D01*
Y-21858D01*
Y-21912D01*
Y-21966D01*
Y-22020D01*
Y-22074D01*
Y-22128D01*
Y-22182D01*
Y-22236D01*
Y-22290D01*
Y-22344D01*
Y-22398D01*
Y-22452D01*
Y-22506D01*
Y-22561D01*
Y-22615D01*
Y-22669D01*
Y-22723D01*
Y-22777D01*
Y-22831D01*
Y-22885D01*
Y-22939D01*
Y-22993D01*
Y-23047D01*
Y-23101D01*
Y-23155D01*
Y-23209D01*
Y-23263D01*
Y-23317D01*
Y-23371D01*
Y-23426D01*
Y-23480D01*
Y-23534D01*
Y-23588D01*
Y-23642D01*
Y-23696D01*
Y-23750D01*
Y-23804D01*
X364861D01*
Y-23750D01*
X364915D01*
Y-23804D01*
X365672D01*
Y-23858D01*
Y-23912D01*
Y-23966D01*
Y-24020D01*
Y-24074D01*
Y-24128D01*
Y-24182D01*
Y-24237D01*
Y-24291D01*
Y-24345D01*
Y-24399D01*
Y-24453D01*
Y-24507D01*
Y-24561D01*
Y-24615D01*
Y-24669D01*
Y-24723D01*
Y-24777D01*
Y-24831D01*
Y-24885D01*
Y-24939D01*
Y-24993D01*
Y-25047D01*
Y-25102D01*
Y-25155D01*
Y-25210D01*
Y-25264D01*
Y-25318D01*
Y-25372D01*
Y-25426D01*
Y-25480D01*
Y-25534D01*
Y-25588D01*
Y-25642D01*
Y-25696D01*
Y-25750D01*
Y-25804D01*
Y-25858D01*
Y-25912D01*
Y-25967D01*
Y-26021D01*
Y-26075D01*
Y-26129D01*
Y-26183D01*
Y-26237D01*
Y-26291D01*
Y-26345D01*
Y-26399D01*
Y-26453D01*
Y-26507D01*
Y-26561D01*
Y-26615D01*
Y-26669D01*
Y-26723D01*
Y-26777D01*
Y-26831D01*
Y-26886D01*
Y-26940D01*
Y-26994D01*
Y-27048D01*
Y-27102D01*
Y-27156D01*
Y-27210D01*
Y-27264D01*
Y-27318D01*
Y-27372D01*
Y-27426D01*
Y-27480D01*
Y-27534D01*
Y-27588D01*
Y-27642D01*
Y-27696D01*
Y-27751D01*
Y-27805D01*
Y-27859D01*
Y-27913D01*
Y-27967D01*
Y-28021D01*
Y-28075D01*
Y-28129D01*
Y-28183D01*
Y-28237D01*
Y-28291D01*
Y-28345D01*
Y-28399D01*
Y-28453D01*
Y-28507D01*
Y-28561D01*
Y-28615D01*
Y-28670D01*
Y-28724D01*
Y-28778D01*
Y-28832D01*
Y-28886D01*
Y-28940D01*
Y-28994D01*
Y-29048D01*
Y-29102D01*
Y-29156D01*
Y-29210D01*
Y-29264D01*
Y-29318D01*
Y-29372D01*
Y-29426D01*
Y-29480D01*
Y-29535D01*
Y-29589D01*
Y-29643D01*
Y-29697D01*
Y-29751D01*
Y-29805D01*
Y-29859D01*
Y-29913D01*
Y-29967D01*
Y-30021D01*
Y-30075D01*
Y-30129D01*
Y-30183D01*
Y-30237D01*
Y-30291D01*
Y-30345D01*
Y-30400D01*
Y-30454D01*
Y-30508D01*
Y-30562D01*
Y-30616D01*
Y-30670D01*
Y-30724D01*
Y-30778D01*
Y-30832D01*
Y-30886D01*
Y-30940D01*
Y-30994D01*
Y-31048D01*
Y-31102D01*
Y-31156D01*
Y-31211D01*
Y-31265D01*
Y-31319D01*
Y-31373D01*
Y-31427D01*
Y-31481D01*
Y-31535D01*
Y-31589D01*
Y-31643D01*
Y-31697D01*
Y-31751D01*
Y-31805D01*
Y-31859D01*
Y-31913D01*
Y-31967D01*
Y-32021D01*
Y-32076D01*
Y-32129D01*
Y-32184D01*
Y-32238D01*
Y-32292D01*
Y-32346D01*
Y-32400D01*
Y-32454D01*
Y-32508D01*
X365726D01*
Y-32562D01*
X365780D01*
Y-32616D01*
X365834D01*
Y-32670D01*
X368213D01*
Y-32616D01*
X368321D01*
Y-32562D01*
X368375D01*
Y-32508D01*
Y-32454D01*
X368429D01*
Y-32400D01*
Y-32346D01*
Y-32292D01*
Y-32238D01*
Y-32184D01*
Y-32129D01*
Y-32076D01*
Y-32021D01*
Y-31967D01*
Y-31913D01*
Y-31859D01*
Y-31805D01*
Y-31751D01*
Y-31697D01*
Y-31643D01*
Y-31589D01*
Y-31535D01*
Y-31481D01*
Y-31427D01*
Y-31373D01*
Y-31319D01*
Y-31265D01*
Y-31211D01*
Y-31156D01*
Y-31102D01*
Y-31048D01*
Y-30994D01*
Y-30940D01*
Y-30886D01*
Y-30832D01*
Y-30778D01*
Y-30724D01*
Y-30670D01*
Y-30616D01*
Y-30562D01*
Y-30508D01*
Y-30454D01*
Y-30400D01*
Y-30345D01*
Y-30291D01*
Y-30237D01*
Y-30183D01*
Y-30129D01*
Y-30075D01*
Y-30021D01*
Y-29967D01*
Y-29913D01*
Y-29859D01*
Y-29805D01*
Y-29751D01*
Y-29697D01*
Y-29643D01*
Y-29589D01*
Y-29535D01*
Y-29480D01*
Y-29426D01*
Y-29372D01*
Y-29318D01*
Y-29264D01*
Y-29210D01*
Y-29156D01*
Y-29102D01*
Y-29048D01*
Y-28994D01*
Y-28940D01*
Y-28886D01*
Y-28832D01*
Y-28778D01*
Y-28724D01*
Y-28670D01*
Y-28615D01*
Y-28561D01*
Y-28507D01*
Y-28453D01*
Y-28399D01*
Y-28345D01*
Y-28291D01*
Y-28237D01*
Y-28183D01*
Y-28129D01*
Y-28075D01*
Y-28021D01*
Y-27967D01*
Y-27913D01*
Y-27859D01*
Y-27805D01*
Y-27751D01*
Y-27696D01*
Y-27642D01*
Y-27588D01*
Y-27534D01*
Y-27480D01*
Y-27426D01*
Y-27372D01*
Y-27318D01*
Y-27264D01*
Y-27210D01*
Y-27156D01*
Y-27102D01*
Y-27048D01*
Y-26994D01*
Y-26940D01*
Y-26886D01*
Y-26831D01*
Y-26777D01*
Y-26723D01*
Y-26669D01*
Y-26615D01*
Y-26561D01*
Y-26507D01*
Y-26453D01*
Y-26399D01*
Y-26345D01*
Y-26291D01*
Y-26237D01*
Y-26183D01*
Y-26129D01*
Y-26075D01*
Y-26021D01*
Y-25967D01*
Y-25912D01*
Y-25858D01*
Y-25804D01*
Y-25750D01*
Y-25696D01*
Y-25642D01*
Y-25588D01*
Y-25534D01*
Y-25480D01*
Y-25426D01*
Y-25372D01*
Y-25318D01*
Y-25264D01*
Y-25210D01*
Y-25155D01*
Y-25102D01*
Y-25047D01*
Y-24993D01*
Y-24939D01*
Y-24885D01*
Y-24831D01*
Y-24777D01*
Y-24723D01*
Y-24669D01*
Y-24615D01*
Y-24561D01*
Y-24507D01*
Y-24453D01*
Y-24399D01*
Y-24345D01*
Y-24291D01*
Y-24237D01*
Y-24182D01*
Y-24128D01*
Y-24074D01*
Y-24020D01*
Y-23966D01*
Y-23912D01*
Y-23858D01*
Y-23804D01*
X370267D01*
Y-23858D01*
Y-23912D01*
Y-23966D01*
Y-24020D01*
Y-24074D01*
Y-24128D01*
Y-24182D01*
Y-24237D01*
Y-24291D01*
Y-24345D01*
Y-24399D01*
Y-24453D01*
Y-24507D01*
Y-24561D01*
Y-24615D01*
Y-24669D01*
Y-24723D01*
Y-24777D01*
Y-24831D01*
Y-24885D01*
Y-24939D01*
Y-24993D01*
Y-25047D01*
Y-25102D01*
Y-25155D01*
Y-25210D01*
Y-25264D01*
Y-25318D01*
Y-25372D01*
Y-25426D01*
Y-25480D01*
Y-25534D01*
Y-25588D01*
Y-25642D01*
Y-25696D01*
Y-25750D01*
Y-25804D01*
Y-25858D01*
Y-25912D01*
Y-25967D01*
Y-26021D01*
Y-26075D01*
Y-26129D01*
Y-26183D01*
Y-26237D01*
Y-26291D01*
Y-26345D01*
Y-26399D01*
Y-26453D01*
Y-26507D01*
Y-26561D01*
Y-26615D01*
Y-26669D01*
Y-26723D01*
Y-26777D01*
Y-26831D01*
Y-26886D01*
Y-26940D01*
Y-26994D01*
Y-27048D01*
Y-27102D01*
Y-27156D01*
Y-27210D01*
Y-27264D01*
Y-27318D01*
Y-27372D01*
Y-27426D01*
Y-27480D01*
Y-27534D01*
Y-27588D01*
Y-27642D01*
Y-27696D01*
Y-27751D01*
Y-27805D01*
Y-27859D01*
Y-27913D01*
Y-27967D01*
Y-28021D01*
Y-28075D01*
Y-28129D01*
Y-28183D01*
Y-28237D01*
Y-28291D01*
Y-28345D01*
Y-28399D01*
Y-28453D01*
Y-28507D01*
Y-28561D01*
Y-28615D01*
Y-28670D01*
Y-28724D01*
Y-28778D01*
Y-28832D01*
Y-28886D01*
Y-28940D01*
Y-28994D01*
Y-29048D01*
Y-29102D01*
Y-29156D01*
Y-29210D01*
Y-29264D01*
Y-29318D01*
Y-29372D01*
Y-29426D01*
Y-29480D01*
Y-29535D01*
Y-29589D01*
Y-29643D01*
Y-29697D01*
Y-29751D01*
Y-29805D01*
Y-29859D01*
Y-29913D01*
Y-29967D01*
Y-30021D01*
Y-30075D01*
Y-30129D01*
Y-30183D01*
Y-30237D01*
Y-30291D01*
Y-30345D01*
Y-30400D01*
Y-30454D01*
Y-30508D01*
Y-30562D01*
Y-30616D01*
Y-30670D01*
Y-30724D01*
Y-30778D01*
Y-30832D01*
Y-30886D01*
Y-30940D01*
Y-30994D01*
Y-31048D01*
Y-31102D01*
Y-31156D01*
Y-31211D01*
Y-31265D01*
Y-31319D01*
Y-31373D01*
Y-31427D01*
Y-31481D01*
Y-31535D01*
Y-31589D01*
Y-31643D01*
Y-31697D01*
Y-31751D01*
Y-31805D01*
Y-31859D01*
Y-31913D01*
Y-31967D01*
Y-32021D01*
Y-32076D01*
Y-32129D01*
Y-32184D01*
Y-32238D01*
Y-32292D01*
Y-32346D01*
Y-32400D01*
Y-32454D01*
X370321D01*
Y-32508D01*
Y-32562D01*
X370375D01*
Y-32616D01*
X370429D01*
Y-32670D01*
X373078D01*
Y-32616D01*
X373186D01*
Y-32562D01*
Y-32508D01*
X373240D01*
Y-32454D01*
Y-32400D01*
Y-32346D01*
Y-32292D01*
Y-32238D01*
Y-32184D01*
Y-32129D01*
Y-32076D01*
Y-32021D01*
Y-31967D01*
Y-31913D01*
Y-31859D01*
Y-31805D01*
Y-31751D01*
Y-31697D01*
Y-31643D01*
Y-31589D01*
Y-31535D01*
Y-31481D01*
Y-31427D01*
Y-31373D01*
Y-31319D01*
Y-31265D01*
Y-31211D01*
Y-31156D01*
Y-31102D01*
Y-31048D01*
Y-30994D01*
Y-30940D01*
Y-30886D01*
Y-30832D01*
Y-30778D01*
Y-30724D01*
Y-30670D01*
Y-30616D01*
Y-30562D01*
Y-30508D01*
Y-30454D01*
Y-30400D01*
Y-30345D01*
Y-30291D01*
Y-30237D01*
Y-30183D01*
Y-30129D01*
Y-30075D01*
Y-30021D01*
Y-29967D01*
Y-29913D01*
Y-29859D01*
Y-29805D01*
Y-29751D01*
Y-29697D01*
Y-29643D01*
Y-29589D01*
Y-29535D01*
Y-29480D01*
Y-29426D01*
Y-29372D01*
Y-29318D01*
Y-29264D01*
Y-29210D01*
Y-29156D01*
Y-29102D01*
Y-29048D01*
Y-28994D01*
Y-28940D01*
Y-28886D01*
Y-28832D01*
Y-28778D01*
Y-28724D01*
Y-28670D01*
Y-28615D01*
Y-28561D01*
Y-28507D01*
Y-28453D01*
Y-28399D01*
Y-28345D01*
Y-28291D01*
Y-28237D01*
Y-28183D01*
Y-28129D01*
Y-28075D01*
Y-28021D01*
Y-27967D01*
Y-27913D01*
Y-27859D01*
Y-27805D01*
Y-27751D01*
Y-27696D01*
Y-27642D01*
Y-27588D01*
Y-27534D01*
Y-27480D01*
Y-27426D01*
Y-27372D01*
Y-27318D01*
Y-27264D01*
Y-27210D01*
Y-27156D01*
Y-27102D01*
Y-27048D01*
Y-26994D01*
Y-26940D01*
Y-26886D01*
Y-26831D01*
Y-26777D01*
Y-26723D01*
Y-26669D01*
Y-26615D01*
Y-26561D01*
Y-26507D01*
Y-26453D01*
Y-26399D01*
Y-26345D01*
Y-26291D01*
Y-26237D01*
Y-26183D01*
Y-26129D01*
Y-26075D01*
Y-26021D01*
Y-25967D01*
Y-25912D01*
Y-25858D01*
Y-25804D01*
Y-25750D01*
Y-25696D01*
Y-25642D01*
Y-25588D01*
Y-25534D01*
Y-25480D01*
Y-25426D01*
Y-25372D01*
Y-25318D01*
Y-25264D01*
Y-25210D01*
Y-25155D01*
Y-25102D01*
Y-25047D01*
Y-24993D01*
Y-24939D01*
Y-24885D01*
Y-24831D01*
Y-24777D01*
Y-24723D01*
Y-24669D01*
Y-24615D01*
Y-24561D01*
Y-24507D01*
Y-24453D01*
Y-24399D01*
Y-24345D01*
Y-24291D01*
Y-24237D01*
Y-24182D01*
Y-24128D01*
Y-24074D01*
Y-24020D01*
Y-23966D01*
Y-23912D01*
Y-23858D01*
Y-23804D01*
Y-23750D01*
Y-23696D01*
Y-23642D01*
Y-23588D01*
Y-23534D01*
Y-23480D01*
Y-23426D01*
Y-23371D01*
Y-23317D01*
Y-23263D01*
Y-23209D01*
Y-23155D01*
Y-23101D01*
Y-23047D01*
Y-22993D01*
Y-22939D01*
Y-22885D01*
Y-22831D01*
Y-22777D01*
Y-22723D01*
Y-22669D01*
Y-22615D01*
Y-22561D01*
Y-22506D01*
Y-22452D01*
Y-22398D01*
Y-22344D01*
Y-22290D01*
Y-22236D01*
Y-22182D01*
Y-22128D01*
Y-22074D01*
Y-22020D01*
Y-21966D01*
Y-21912D01*
Y-21858D01*
Y-21804D01*
Y-21750D01*
Y-21696D01*
Y-21642D01*
Y-21587D01*
Y-21533D01*
Y-21479D01*
Y-21425D01*
Y-21371D01*
Y-21317D01*
Y-21263D01*
Y-21209D01*
Y-21155D01*
Y-21101D01*
X373186D01*
Y-21047D01*
Y-20993D01*
X373132D01*
Y-20939D01*
X372970D01*
Y-20885D01*
D02*
G37*
G36*
X375187Y-33643D02*
X368699D01*
Y-33697D01*
X368645D01*
Y-33643D01*
X368537D01*
Y-33697D01*
X368375D01*
Y-33751D01*
X368321D01*
Y-33806D01*
X368267D01*
Y-33860D01*
Y-33914D01*
Y-33968D01*
Y-34022D01*
Y-34076D01*
Y-34130D01*
Y-34184D01*
Y-34238D01*
Y-34292D01*
Y-34346D01*
Y-34400D01*
Y-34454D01*
Y-34508D01*
Y-34562D01*
Y-34616D01*
Y-34670D01*
Y-34725D01*
Y-34779D01*
Y-34833D01*
Y-34887D01*
Y-34941D01*
Y-34995D01*
Y-35049D01*
Y-35103D01*
Y-35157D01*
Y-35211D01*
Y-35265D01*
Y-35319D01*
Y-35373D01*
Y-35427D01*
Y-35481D01*
Y-35535D01*
Y-35590D01*
Y-35644D01*
Y-35698D01*
Y-35752D01*
Y-35806D01*
Y-35860D01*
Y-35914D01*
Y-35968D01*
Y-36022D01*
Y-36076D01*
Y-36130D01*
Y-36184D01*
Y-36238D01*
Y-36292D01*
Y-36346D01*
Y-36400D01*
X368321D01*
Y-36454D01*
X368375D01*
Y-36509D01*
X368537D01*
Y-36563D01*
X368753D01*
Y-36509D01*
X368807D01*
Y-36563D01*
X374159D01*
Y-36617D01*
X374214D01*
Y-36671D01*
X374268D01*
Y-36725D01*
Y-36779D01*
Y-36833D01*
Y-36887D01*
Y-36941D01*
Y-36995D01*
Y-37049D01*
Y-37103D01*
Y-37157D01*
Y-37211D01*
Y-37265D01*
Y-37319D01*
Y-37374D01*
Y-37428D01*
Y-37482D01*
Y-37536D01*
Y-37590D01*
Y-37644D01*
Y-37698D01*
Y-37752D01*
Y-37806D01*
Y-37860D01*
Y-37914D01*
Y-37968D01*
Y-38022D01*
Y-38076D01*
Y-38130D01*
Y-38184D01*
Y-38238D01*
Y-38293D01*
Y-38347D01*
Y-38401D01*
Y-38455D01*
Y-38509D01*
Y-38563D01*
Y-38617D01*
Y-38671D01*
Y-38725D01*
Y-38779D01*
Y-38833D01*
Y-38887D01*
Y-38941D01*
Y-38995D01*
Y-39050D01*
Y-39103D01*
Y-39158D01*
Y-39212D01*
Y-39266D01*
Y-39320D01*
Y-39374D01*
Y-39428D01*
Y-39482D01*
Y-39536D01*
Y-39590D01*
Y-39644D01*
Y-39698D01*
Y-39752D01*
Y-39806D01*
Y-39860D01*
Y-39915D01*
Y-39968D01*
Y-40023D01*
Y-40077D01*
Y-40131D01*
Y-40185D01*
Y-40239D01*
Y-40293D01*
Y-40347D01*
Y-40401D01*
Y-40455D01*
Y-40509D01*
Y-40563D01*
Y-40617D01*
Y-40671D01*
Y-40725D01*
Y-40780D01*
Y-40834D01*
Y-40888D01*
Y-40942D01*
Y-40996D01*
Y-41050D01*
Y-41104D01*
Y-41158D01*
Y-41212D01*
Y-41266D01*
Y-41320D01*
Y-41374D01*
Y-41428D01*
Y-41482D01*
Y-41536D01*
Y-41590D01*
Y-41644D01*
Y-41699D01*
Y-41753D01*
Y-41807D01*
Y-41861D01*
Y-41915D01*
Y-41969D01*
Y-42023D01*
Y-42077D01*
Y-42131D01*
Y-42185D01*
Y-42239D01*
Y-42293D01*
Y-42347D01*
Y-42401D01*
X374214D01*
Y-42455D01*
Y-42509D01*
X374105D01*
Y-42564D01*
X368483D01*
Y-42618D01*
X368375D01*
Y-42672D01*
X368321D01*
Y-42726D01*
X368267D01*
Y-42780D01*
Y-42834D01*
Y-42888D01*
Y-42942D01*
Y-42996D01*
Y-43050D01*
Y-43104D01*
Y-43158D01*
Y-43212D01*
Y-43266D01*
Y-43320D01*
Y-43374D01*
Y-43429D01*
Y-43483D01*
Y-43537D01*
Y-43591D01*
Y-43645D01*
Y-43699D01*
Y-43753D01*
Y-43807D01*
Y-43861D01*
Y-43915D01*
Y-43969D01*
Y-44023D01*
Y-44077D01*
Y-44131D01*
Y-44185D01*
Y-44239D01*
Y-44293D01*
Y-44348D01*
Y-44402D01*
Y-44456D01*
Y-44510D01*
Y-44564D01*
Y-44618D01*
Y-44672D01*
Y-44726D01*
Y-44780D01*
Y-44834D01*
Y-44888D01*
Y-44942D01*
Y-44996D01*
Y-45050D01*
Y-45104D01*
Y-45158D01*
Y-45213D01*
Y-45267D01*
X368321D01*
Y-45321D01*
X368375D01*
Y-45375D01*
X368429D01*
Y-45429D01*
X375295D01*
Y-45375D01*
X375457D01*
Y-45321D01*
X375565D01*
Y-45267D01*
X375619D01*
Y-45213D01*
X375673D01*
Y-45158D01*
X375727D01*
Y-45104D01*
X375781D01*
Y-45050D01*
X375835D01*
Y-44996D01*
X375889D01*
Y-44942D01*
X375943D01*
Y-44888D01*
X375997D01*
Y-44834D01*
X376052D01*
Y-44780D01*
X376106D01*
Y-44726D01*
X376160D01*
Y-44672D01*
X376214D01*
Y-44618D01*
X376268D01*
Y-44564D01*
X376322D01*
Y-44510D01*
X376376D01*
Y-44456D01*
X376430D01*
Y-44402D01*
X376484D01*
Y-44348D01*
X376538D01*
Y-44293D01*
X376592D01*
Y-44239D01*
X376646D01*
Y-44185D01*
X376700D01*
Y-44131D01*
X376754D01*
Y-44077D01*
X376809D01*
Y-44023D01*
X376863D01*
Y-43969D01*
X376917D01*
Y-43915D01*
X376971D01*
Y-43861D01*
X377025D01*
Y-43807D01*
X377079D01*
Y-43753D01*
X377133D01*
Y-43699D01*
Y-43645D01*
X377187D01*
Y-43591D01*
Y-43537D01*
Y-43483D01*
X377241D01*
Y-43429D01*
Y-43374D01*
Y-43320D01*
Y-43266D01*
Y-43212D01*
Y-43158D01*
Y-43104D01*
Y-43050D01*
Y-42996D01*
Y-42942D01*
Y-42888D01*
Y-42834D01*
Y-42780D01*
Y-42726D01*
Y-42672D01*
Y-42618D01*
Y-42564D01*
Y-42509D01*
Y-42455D01*
Y-42401D01*
Y-42347D01*
Y-42293D01*
Y-42239D01*
Y-42185D01*
Y-42131D01*
Y-42077D01*
Y-42023D01*
Y-41969D01*
Y-41915D01*
Y-41861D01*
Y-41807D01*
Y-41753D01*
Y-41699D01*
Y-41644D01*
Y-41590D01*
Y-41536D01*
Y-41482D01*
Y-41428D01*
Y-41374D01*
Y-41320D01*
Y-41266D01*
Y-41212D01*
Y-41158D01*
Y-41104D01*
Y-41050D01*
Y-40996D01*
Y-40942D01*
Y-40888D01*
Y-40834D01*
Y-40780D01*
Y-40725D01*
Y-40671D01*
Y-40617D01*
Y-40563D01*
Y-40509D01*
Y-40455D01*
Y-40401D01*
Y-40347D01*
Y-40293D01*
Y-40239D01*
Y-40185D01*
Y-40131D01*
Y-40077D01*
Y-40023D01*
Y-39968D01*
Y-39915D01*
Y-39860D01*
Y-39806D01*
Y-39752D01*
Y-39698D01*
Y-39644D01*
Y-39590D01*
Y-39536D01*
Y-39482D01*
Y-39428D01*
Y-39374D01*
Y-39320D01*
Y-39266D01*
Y-39212D01*
Y-39158D01*
Y-39103D01*
Y-39050D01*
Y-38995D01*
Y-38941D01*
Y-38887D01*
Y-38833D01*
Y-38779D01*
Y-38725D01*
Y-38671D01*
Y-38617D01*
Y-38563D01*
Y-38509D01*
Y-38455D01*
Y-38401D01*
Y-38347D01*
Y-38293D01*
Y-38238D01*
Y-38184D01*
Y-38130D01*
Y-38076D01*
Y-38022D01*
Y-37968D01*
Y-37914D01*
Y-37860D01*
Y-37806D01*
Y-37752D01*
Y-37698D01*
Y-37644D01*
Y-37590D01*
Y-37536D01*
Y-37482D01*
Y-37428D01*
Y-37374D01*
Y-37319D01*
Y-37265D01*
Y-37211D01*
Y-37157D01*
Y-37103D01*
Y-37049D01*
Y-36995D01*
Y-36941D01*
Y-36887D01*
Y-36833D01*
Y-36779D01*
Y-36725D01*
Y-36671D01*
Y-36617D01*
Y-36563D01*
Y-36509D01*
Y-36454D01*
Y-36400D01*
Y-36346D01*
Y-36292D01*
Y-36238D01*
Y-36184D01*
Y-36130D01*
Y-36076D01*
Y-36022D01*
Y-35968D01*
Y-35914D01*
Y-35860D01*
Y-35806D01*
Y-35752D01*
Y-35698D01*
Y-35644D01*
X377187D01*
Y-35590D01*
Y-35535D01*
Y-35481D01*
Y-35427D01*
X377133D01*
Y-35373D01*
Y-35319D01*
X377079D01*
Y-35265D01*
X377025D01*
Y-35211D01*
X376971D01*
Y-35157D01*
X376917D01*
Y-35103D01*
X376863D01*
Y-35049D01*
X376809D01*
Y-34995D01*
X376754D01*
Y-34941D01*
X376700D01*
Y-34887D01*
X376646D01*
Y-34833D01*
X376592D01*
Y-34779D01*
X376538D01*
Y-34725D01*
X376484D01*
Y-34670D01*
X376430D01*
Y-34616D01*
X376376D01*
Y-34562D01*
X376322D01*
Y-34508D01*
X376268D01*
Y-34454D01*
X376214D01*
Y-34400D01*
X376160D01*
Y-34346D01*
X376106D01*
Y-34292D01*
X376052D01*
Y-34238D01*
X375997D01*
Y-34184D01*
X375943D01*
Y-34130D01*
X375889D01*
Y-34076D01*
X375835D01*
Y-34022D01*
X375781D01*
Y-33968D01*
X375727D01*
Y-33914D01*
X375673D01*
Y-33860D01*
X375619D01*
Y-33806D01*
X375511D01*
Y-33751D01*
X375349D01*
Y-33697D01*
X375187D01*
Y-33643D01*
D02*
G37*
G36*
X363779Y-14451D02*
X362806D01*
Y-14505D01*
X362590D01*
Y-14559D01*
X362482D01*
Y-14614D01*
X362428D01*
Y-14668D01*
X362374D01*
Y-14722D01*
X362320D01*
Y-14776D01*
X362266D01*
Y-14830D01*
X362212D01*
Y-14884D01*
X362158D01*
Y-14938D01*
X362104D01*
Y-14992D01*
X362050D01*
Y-15046D01*
X361996D01*
Y-15100D01*
X361941D01*
Y-15154D01*
X361887D01*
Y-15208D01*
X361833D01*
Y-15262D01*
X361779D01*
Y-15316D01*
X361725D01*
Y-15370D01*
X361671D01*
Y-15424D01*
X361617D01*
Y-15478D01*
X361563D01*
Y-15532D01*
X361509D01*
Y-15587D01*
X361455D01*
Y-15641D01*
X361401D01*
Y-15695D01*
X361347D01*
Y-15749D01*
X361293D01*
Y-15803D01*
X361239D01*
Y-15857D01*
X361185D01*
Y-15911D01*
X361130D01*
Y-15965D01*
X361076D01*
Y-16019D01*
X361022D01*
Y-16073D01*
X360968D01*
Y-16127D01*
Y-16181D01*
X360914D01*
Y-16235D01*
Y-16289D01*
Y-16343D01*
Y-16398D01*
X360860D01*
Y-16452D01*
Y-16506D01*
Y-16560D01*
Y-16614D01*
Y-16668D01*
Y-16722D01*
Y-16776D01*
Y-16830D01*
Y-16884D01*
Y-16938D01*
Y-16992D01*
Y-17046D01*
Y-17100D01*
Y-17154D01*
Y-17208D01*
Y-17263D01*
Y-17317D01*
Y-17371D01*
Y-17425D01*
Y-17479D01*
Y-17533D01*
Y-17587D01*
Y-17641D01*
Y-17695D01*
Y-17749D01*
Y-17803D01*
Y-17857D01*
Y-17911D01*
Y-17965D01*
Y-18019D01*
Y-18073D01*
Y-18127D01*
Y-18181D01*
Y-18236D01*
Y-18290D01*
Y-18344D01*
Y-18398D01*
Y-18452D01*
Y-18506D01*
Y-18560D01*
Y-18614D01*
Y-18668D01*
Y-18722D01*
Y-18776D01*
Y-18830D01*
Y-18884D01*
Y-18938D01*
Y-18993D01*
Y-19047D01*
Y-19101D01*
Y-19155D01*
Y-19209D01*
Y-19263D01*
Y-19317D01*
Y-19371D01*
Y-19425D01*
Y-19479D01*
Y-19533D01*
Y-19587D01*
Y-19641D01*
Y-19695D01*
Y-19749D01*
Y-19803D01*
Y-19858D01*
Y-19911D01*
Y-19966D01*
Y-20020D01*
Y-20074D01*
Y-20128D01*
Y-20182D01*
Y-20236D01*
Y-20290D01*
Y-20344D01*
Y-20398D01*
Y-20452D01*
Y-20506D01*
Y-20560D01*
Y-20614D01*
Y-20668D01*
Y-20722D01*
Y-20776D01*
Y-20831D01*
Y-20885D01*
Y-20939D01*
Y-20993D01*
Y-21047D01*
Y-21101D01*
Y-21155D01*
Y-21209D01*
Y-21263D01*
Y-21317D01*
Y-21371D01*
Y-21425D01*
Y-21479D01*
Y-21533D01*
Y-21587D01*
Y-21642D01*
Y-21696D01*
Y-21750D01*
Y-21804D01*
Y-21858D01*
Y-21912D01*
Y-21966D01*
Y-22020D01*
Y-22074D01*
Y-22128D01*
Y-22182D01*
Y-22236D01*
Y-22290D01*
Y-22344D01*
Y-22398D01*
Y-22452D01*
Y-22506D01*
Y-22561D01*
Y-22615D01*
Y-22669D01*
Y-22723D01*
Y-22777D01*
Y-22831D01*
Y-22885D01*
Y-22939D01*
Y-22993D01*
Y-23047D01*
Y-23101D01*
Y-23155D01*
Y-23209D01*
Y-23263D01*
Y-23317D01*
Y-23371D01*
Y-23426D01*
Y-23480D01*
Y-23534D01*
Y-23588D01*
Y-23642D01*
Y-23696D01*
Y-23750D01*
Y-23804D01*
Y-23858D01*
Y-23912D01*
Y-23966D01*
Y-24020D01*
Y-24074D01*
Y-24128D01*
Y-24182D01*
Y-24237D01*
Y-24291D01*
Y-24345D01*
Y-24399D01*
Y-24453D01*
Y-24507D01*
Y-24561D01*
Y-24615D01*
Y-24669D01*
Y-24723D01*
Y-24777D01*
Y-24831D01*
Y-24885D01*
Y-24939D01*
Y-24993D01*
Y-25047D01*
Y-25102D01*
Y-25155D01*
Y-25210D01*
Y-25264D01*
Y-25318D01*
Y-25372D01*
Y-25426D01*
Y-25480D01*
Y-25534D01*
Y-25588D01*
Y-25642D01*
Y-25696D01*
Y-25750D01*
Y-25804D01*
Y-25858D01*
Y-25912D01*
Y-25967D01*
Y-26021D01*
Y-26075D01*
Y-26129D01*
Y-26183D01*
Y-26237D01*
Y-26291D01*
Y-26345D01*
Y-26399D01*
Y-26453D01*
Y-26507D01*
Y-26561D01*
Y-26615D01*
Y-26669D01*
Y-26723D01*
Y-26777D01*
Y-26831D01*
Y-26886D01*
Y-26940D01*
Y-26994D01*
Y-27048D01*
Y-27102D01*
Y-27156D01*
Y-27210D01*
Y-27264D01*
Y-27318D01*
Y-27372D01*
Y-27426D01*
Y-27480D01*
Y-27534D01*
Y-27588D01*
Y-27642D01*
Y-27696D01*
Y-27751D01*
Y-27805D01*
Y-27859D01*
Y-27913D01*
Y-27967D01*
Y-28021D01*
Y-28075D01*
Y-28129D01*
Y-28183D01*
Y-28237D01*
Y-28291D01*
Y-28345D01*
Y-28399D01*
Y-28453D01*
Y-28507D01*
Y-28561D01*
Y-28615D01*
Y-28670D01*
Y-28724D01*
Y-28778D01*
Y-28832D01*
Y-28886D01*
Y-28940D01*
Y-28994D01*
Y-29048D01*
Y-29102D01*
Y-29156D01*
Y-29210D01*
Y-29264D01*
Y-29318D01*
Y-29372D01*
Y-29426D01*
Y-29480D01*
Y-29535D01*
Y-29589D01*
Y-29643D01*
Y-29697D01*
Y-29751D01*
Y-29805D01*
Y-29859D01*
Y-29913D01*
Y-29967D01*
Y-30021D01*
Y-30075D01*
Y-30129D01*
Y-30183D01*
Y-30237D01*
Y-30291D01*
Y-30345D01*
Y-30400D01*
Y-30454D01*
Y-30508D01*
Y-30562D01*
Y-30616D01*
Y-30670D01*
Y-30724D01*
Y-30778D01*
Y-30832D01*
Y-30886D01*
Y-30940D01*
Y-30994D01*
Y-31048D01*
Y-31102D01*
Y-31156D01*
Y-31211D01*
Y-31265D01*
Y-31319D01*
Y-31373D01*
Y-31427D01*
Y-31481D01*
Y-31535D01*
Y-31589D01*
Y-31643D01*
Y-31697D01*
Y-31751D01*
Y-31805D01*
Y-31859D01*
Y-31913D01*
Y-31967D01*
Y-32021D01*
Y-32076D01*
Y-32129D01*
Y-32184D01*
Y-32238D01*
Y-32292D01*
Y-32346D01*
Y-32400D01*
Y-32454D01*
Y-32508D01*
Y-32562D01*
Y-32616D01*
Y-32670D01*
Y-32724D01*
Y-32778D01*
Y-32832D01*
Y-32886D01*
Y-32941D01*
Y-32994D01*
Y-33049D01*
Y-33103D01*
Y-33157D01*
Y-33211D01*
X360914D01*
Y-33265D01*
Y-33319D01*
Y-33373D01*
Y-33427D01*
X360968D01*
Y-33481D01*
Y-33535D01*
X361022D01*
Y-33589D01*
Y-33643D01*
X361076D01*
Y-33697D01*
Y-33751D01*
X361130D01*
Y-33806D01*
X361185D01*
Y-33860D01*
Y-33914D01*
X361239D01*
Y-33968D01*
X361293D01*
Y-34022D01*
X361347D01*
Y-34076D01*
X361401D01*
Y-34130D01*
X361455D01*
Y-34184D01*
X361509D01*
Y-34238D01*
X361563D01*
Y-34292D01*
X361617D01*
Y-34346D01*
X361671D01*
Y-34400D01*
X361725D01*
Y-34454D01*
X361779D01*
Y-34508D01*
X361833D01*
Y-34562D01*
X361887D01*
Y-34616D01*
X361941D01*
Y-34670D01*
X361996D01*
Y-34725D01*
X362050D01*
Y-34779D01*
X362104D01*
Y-34833D01*
X362158D01*
Y-34887D01*
X362212D01*
Y-34941D01*
X362266D01*
Y-34995D01*
X362320D01*
Y-35049D01*
X362374D01*
Y-35103D01*
X362428D01*
Y-35157D01*
X362482D01*
Y-35211D01*
X362536D01*
Y-35265D01*
X362590D01*
Y-35319D01*
X362644D01*
Y-35373D01*
X362698D01*
Y-35427D01*
X362752D01*
Y-35481D01*
X362806D01*
Y-35535D01*
X362914D01*
Y-35590D01*
X362969D01*
Y-35644D01*
X363023D01*
Y-35698D01*
X363077D01*
Y-35752D01*
X363131D01*
Y-35806D01*
X363185D01*
Y-35860D01*
X363239D01*
Y-35914D01*
X363293D01*
Y-35968D01*
X363347D01*
Y-36022D01*
X363401D01*
Y-36076D01*
X363455D01*
Y-36130D01*
X363509D01*
Y-36184D01*
X363563D01*
Y-36238D01*
X363617D01*
Y-36292D01*
X363671D01*
Y-36346D01*
X363725D01*
Y-36400D01*
X363779D01*
Y-36454D01*
X363834D01*
Y-36509D01*
X363888D01*
Y-36563D01*
X363942D01*
Y-36617D01*
X363996D01*
Y-36671D01*
X364050D01*
Y-36725D01*
X364104D01*
Y-36779D01*
X364158D01*
Y-36833D01*
X364212D01*
Y-36887D01*
X364266D01*
Y-36941D01*
X364320D01*
Y-36995D01*
X364374D01*
Y-37049D01*
X364428D01*
Y-37103D01*
X364482D01*
Y-37157D01*
X364536D01*
Y-37211D01*
X364591D01*
Y-37265D01*
X364645D01*
Y-37319D01*
X364699D01*
Y-37374D01*
X364753D01*
Y-37428D01*
X364807D01*
Y-37482D01*
X364861D01*
Y-37536D01*
X364915D01*
Y-37590D01*
X364969D01*
Y-37644D01*
X365023D01*
Y-37698D01*
X365077D01*
Y-37752D01*
X365131D01*
Y-37806D01*
X365185D01*
Y-37860D01*
X365239D01*
Y-37914D01*
X365293D01*
Y-37968D01*
X365347D01*
Y-38022D01*
X365401D01*
Y-38076D01*
X365456D01*
Y-38130D01*
X365510D01*
Y-38184D01*
X365564D01*
Y-38238D01*
X365618D01*
Y-38293D01*
X365672D01*
Y-38347D01*
X365726D01*
Y-38401D01*
X365780D01*
Y-38455D01*
X365834D01*
Y-38509D01*
X365888D01*
Y-38563D01*
X365942D01*
Y-38617D01*
X365996D01*
Y-38671D01*
X366050D01*
Y-38725D01*
X366104D01*
Y-38779D01*
X366158D01*
Y-38833D01*
X366212D01*
Y-38887D01*
X366266D01*
Y-38941D01*
X366320D01*
Y-38995D01*
X366374D01*
Y-39050D01*
X366429D01*
Y-39103D01*
X366483D01*
Y-39158D01*
X366537D01*
Y-39212D01*
X366591D01*
Y-39266D01*
X366645D01*
Y-39320D01*
X366699D01*
Y-39374D01*
X366753D01*
Y-39428D01*
X366807D01*
Y-39482D01*
X366861D01*
Y-39536D01*
X366915D01*
Y-39590D01*
X366969D01*
Y-39644D01*
X367023D01*
Y-39698D01*
X367077D01*
Y-39752D01*
X367131D01*
Y-39806D01*
X367185D01*
Y-39860D01*
X367239D01*
Y-39915D01*
X367294D01*
Y-39968D01*
X367348D01*
Y-40023D01*
X367402D01*
Y-40077D01*
X367510D01*
Y-40131D01*
X367564D01*
Y-40185D01*
X367618D01*
Y-40239D01*
X367672D01*
Y-40293D01*
X367726D01*
Y-40347D01*
X367780D01*
Y-40401D01*
X367834D01*
Y-40455D01*
X367888D01*
Y-40509D01*
X367942D01*
Y-40563D01*
X367996D01*
Y-40617D01*
X368050D01*
Y-40671D01*
X368105D01*
Y-40725D01*
X368159D01*
Y-40780D01*
X368213D01*
Y-40834D01*
X368267D01*
Y-40888D01*
X368321D01*
Y-40942D01*
X368375D01*
Y-40996D01*
X368429D01*
Y-41050D01*
X368483D01*
Y-41104D01*
X368537D01*
Y-41158D01*
X368591D01*
Y-41212D01*
X368645D01*
Y-41266D01*
X368699D01*
Y-41320D01*
X368753D01*
Y-41374D01*
X368861D01*
Y-41320D01*
X368915D01*
Y-41266D01*
X368969D01*
Y-41212D01*
X369023D01*
Y-41158D01*
X369078D01*
Y-41104D01*
X369132D01*
Y-41050D01*
X369186D01*
Y-40996D01*
X369240D01*
Y-40942D01*
X369294D01*
Y-40888D01*
X369348D01*
Y-40834D01*
Y-40780D01*
X369402D01*
Y-40725D01*
X369456D01*
Y-40671D01*
Y-40617D01*
X369510D01*
Y-40563D01*
X369564D01*
Y-40509D01*
Y-40455D01*
Y-40401D01*
Y-40347D01*
Y-40293D01*
Y-40239D01*
Y-40185D01*
Y-40131D01*
Y-40077D01*
Y-40023D01*
Y-39968D01*
Y-39915D01*
Y-39860D01*
Y-39806D01*
Y-39752D01*
Y-39698D01*
Y-39644D01*
Y-39590D01*
Y-39536D01*
Y-39482D01*
Y-39428D01*
Y-39374D01*
Y-39320D01*
Y-39266D01*
Y-39212D01*
Y-39158D01*
Y-39103D01*
Y-39050D01*
Y-38995D01*
Y-38941D01*
Y-38887D01*
Y-38833D01*
Y-38779D01*
Y-38725D01*
Y-38671D01*
Y-38617D01*
Y-38563D01*
Y-38509D01*
Y-38455D01*
Y-38401D01*
Y-38347D01*
Y-38293D01*
Y-38238D01*
Y-38184D01*
Y-38130D01*
X369510D01*
Y-38076D01*
Y-38022D01*
X369456D01*
Y-37968D01*
Y-37914D01*
X369402D01*
Y-37860D01*
X369348D01*
Y-37806D01*
Y-37752D01*
X369294D01*
Y-37698D01*
X369240D01*
Y-37644D01*
X369186D01*
Y-37590D01*
X369132D01*
Y-37536D01*
X369078D01*
Y-37482D01*
X369023D01*
Y-37428D01*
X368969D01*
Y-37374D01*
X368915D01*
Y-37319D01*
X368861D01*
Y-37265D01*
X368807D01*
Y-37211D01*
X368753D01*
Y-37157D01*
X368699D01*
Y-37103D01*
X368645D01*
Y-37049D01*
X368591D01*
Y-36995D01*
X368537D01*
Y-36941D01*
X368483D01*
Y-36887D01*
X368375D01*
Y-36833D01*
X368321D01*
Y-36779D01*
X368267D01*
Y-36725D01*
X368213D01*
Y-36671D01*
X368159D01*
Y-36617D01*
X368105D01*
Y-36563D01*
X368050D01*
Y-36509D01*
X367996D01*
Y-36454D01*
X367942D01*
Y-36400D01*
X367888D01*
Y-36346D01*
X367834D01*
Y-36292D01*
X367780D01*
Y-36238D01*
X367726D01*
Y-36184D01*
X367672D01*
Y-36130D01*
X367618D01*
Y-36076D01*
X367564D01*
Y-36022D01*
X367510D01*
Y-35968D01*
X367456D01*
Y-35914D01*
X367402D01*
Y-35860D01*
X367348D01*
Y-35806D01*
X367294D01*
Y-35752D01*
X367239D01*
Y-35698D01*
X367185D01*
Y-35644D01*
X367131D01*
Y-35590D01*
X367077D01*
Y-35535D01*
X367023D01*
Y-35481D01*
X366969D01*
Y-35427D01*
X366915D01*
Y-35373D01*
X366861D01*
Y-35319D01*
X366807D01*
Y-35265D01*
X366753D01*
Y-35211D01*
X366699D01*
Y-35157D01*
X366645D01*
Y-35103D01*
X366591D01*
Y-35049D01*
X366537D01*
Y-34995D01*
X366483D01*
Y-34941D01*
X366429D01*
Y-34887D01*
X366374D01*
Y-34833D01*
X366320D01*
Y-34779D01*
X366266D01*
Y-34725D01*
X366212D01*
Y-34670D01*
X366158D01*
Y-34616D01*
X366104D01*
Y-34562D01*
X366050D01*
Y-34508D01*
X365996D01*
Y-34454D01*
X365942D01*
Y-34400D01*
X365888D01*
Y-34346D01*
X365834D01*
Y-34292D01*
X365780D01*
Y-34238D01*
X365726D01*
Y-34184D01*
X365672D01*
Y-34130D01*
X365618D01*
Y-34076D01*
X365564D01*
Y-34022D01*
X365510D01*
Y-33968D01*
X365456D01*
Y-33914D01*
X365401D01*
Y-33860D01*
X365347D01*
Y-33806D01*
X365293D01*
Y-33751D01*
X365239D01*
Y-33697D01*
X365185D01*
Y-33643D01*
X365131D01*
Y-33589D01*
X365077D01*
Y-33535D01*
X365023D01*
Y-33481D01*
X364969D01*
Y-33427D01*
X364915D01*
Y-33373D01*
X364861D01*
Y-33319D01*
X364807D01*
Y-33265D01*
X364699D01*
Y-33211D01*
X364645D01*
Y-33157D01*
X364591D01*
Y-33103D01*
X364536D01*
Y-33049D01*
X364482D01*
Y-32994D01*
X364428D01*
Y-32941D01*
X364374D01*
Y-32886D01*
X364320D01*
Y-32832D01*
X364266D01*
Y-32778D01*
X364212D01*
Y-32724D01*
X364158D01*
Y-32670D01*
X364104D01*
Y-32616D01*
X364050D01*
Y-32562D01*
X363996D01*
Y-32508D01*
X363942D01*
Y-32454D01*
X363888D01*
Y-32400D01*
X363834D01*
Y-32346D01*
X363779D01*
Y-32292D01*
Y-32238D01*
Y-32184D01*
Y-32129D01*
Y-32076D01*
Y-32021D01*
Y-31967D01*
Y-31913D01*
Y-31859D01*
Y-31805D01*
Y-31751D01*
Y-31697D01*
Y-31643D01*
Y-31589D01*
Y-31535D01*
Y-31481D01*
Y-31427D01*
Y-31373D01*
Y-31319D01*
Y-31265D01*
Y-31211D01*
Y-31156D01*
Y-31102D01*
Y-31048D01*
Y-30994D01*
Y-30940D01*
Y-30886D01*
Y-30832D01*
Y-30778D01*
Y-30724D01*
Y-30670D01*
Y-30616D01*
Y-30562D01*
Y-30508D01*
Y-30454D01*
Y-30400D01*
Y-30345D01*
Y-30291D01*
Y-30237D01*
Y-30183D01*
Y-30129D01*
Y-30075D01*
Y-30021D01*
Y-29967D01*
Y-29913D01*
Y-29859D01*
Y-29805D01*
Y-29751D01*
Y-29697D01*
Y-29643D01*
Y-29589D01*
Y-29535D01*
Y-29480D01*
Y-29426D01*
Y-29372D01*
Y-29318D01*
Y-29264D01*
Y-29210D01*
Y-29156D01*
Y-29102D01*
Y-29048D01*
Y-28994D01*
Y-28940D01*
Y-28886D01*
Y-28832D01*
Y-28778D01*
Y-28724D01*
Y-28670D01*
Y-28615D01*
Y-28561D01*
Y-28507D01*
Y-28453D01*
Y-28399D01*
Y-28345D01*
Y-28291D01*
Y-28237D01*
Y-28183D01*
Y-28129D01*
Y-28075D01*
Y-28021D01*
Y-27967D01*
Y-27913D01*
Y-27859D01*
Y-27805D01*
Y-27751D01*
Y-27696D01*
Y-27642D01*
Y-27588D01*
Y-27534D01*
Y-27480D01*
Y-27426D01*
Y-27372D01*
Y-27318D01*
Y-27264D01*
Y-27210D01*
Y-27156D01*
Y-27102D01*
Y-27048D01*
Y-26994D01*
Y-26940D01*
Y-26886D01*
Y-26831D01*
Y-26777D01*
Y-26723D01*
Y-26669D01*
Y-26615D01*
Y-26561D01*
Y-26507D01*
Y-26453D01*
Y-26399D01*
Y-26345D01*
Y-26291D01*
Y-26237D01*
Y-26183D01*
Y-26129D01*
Y-26075D01*
Y-26021D01*
Y-25967D01*
Y-25912D01*
Y-25858D01*
Y-25804D01*
Y-25750D01*
Y-25696D01*
Y-25642D01*
Y-25588D01*
Y-25534D01*
Y-25480D01*
Y-25426D01*
Y-25372D01*
Y-25318D01*
Y-25264D01*
Y-25210D01*
Y-25155D01*
Y-25102D01*
Y-25047D01*
Y-24993D01*
Y-24939D01*
Y-24885D01*
Y-24831D01*
Y-24777D01*
Y-24723D01*
Y-24669D01*
Y-24615D01*
Y-24561D01*
Y-24507D01*
Y-24453D01*
Y-24399D01*
Y-24345D01*
Y-24291D01*
Y-24237D01*
Y-24182D01*
Y-24128D01*
Y-24074D01*
Y-24020D01*
Y-23966D01*
Y-23912D01*
Y-23858D01*
Y-23804D01*
Y-23750D01*
Y-23696D01*
Y-23642D01*
Y-23588D01*
Y-23534D01*
Y-23480D01*
Y-23426D01*
Y-23371D01*
Y-23317D01*
Y-23263D01*
Y-23209D01*
Y-23155D01*
Y-23101D01*
Y-23047D01*
Y-22993D01*
Y-22939D01*
Y-22885D01*
Y-22831D01*
Y-22777D01*
Y-22723D01*
Y-22669D01*
Y-22615D01*
Y-22561D01*
Y-22506D01*
Y-22452D01*
Y-22398D01*
Y-22344D01*
Y-22290D01*
Y-22236D01*
Y-22182D01*
Y-22128D01*
Y-22074D01*
Y-22020D01*
Y-21966D01*
Y-21912D01*
Y-21858D01*
Y-21804D01*
Y-21750D01*
Y-21696D01*
Y-21642D01*
Y-21587D01*
Y-21533D01*
Y-21479D01*
Y-21425D01*
Y-21371D01*
Y-21317D01*
Y-21263D01*
Y-21209D01*
Y-21155D01*
Y-21101D01*
Y-21047D01*
Y-20993D01*
Y-20939D01*
Y-20885D01*
Y-20831D01*
Y-20776D01*
Y-20722D01*
Y-20668D01*
Y-20614D01*
Y-20560D01*
Y-20506D01*
Y-20452D01*
Y-20398D01*
Y-20344D01*
Y-20290D01*
Y-20236D01*
Y-20182D01*
Y-20128D01*
Y-20074D01*
Y-20020D01*
Y-19966D01*
Y-19911D01*
Y-19858D01*
Y-19803D01*
Y-19749D01*
Y-19695D01*
Y-19641D01*
Y-19587D01*
Y-19533D01*
Y-19479D01*
Y-19425D01*
Y-19371D01*
Y-19317D01*
Y-19263D01*
Y-19209D01*
Y-19155D01*
Y-19101D01*
Y-19047D01*
Y-18993D01*
Y-18938D01*
Y-18884D01*
Y-18830D01*
Y-18776D01*
Y-18722D01*
Y-18668D01*
Y-18614D01*
Y-18560D01*
Y-18506D01*
Y-18452D01*
Y-18398D01*
Y-18344D01*
Y-18290D01*
Y-18236D01*
Y-18181D01*
Y-18127D01*
Y-18073D01*
Y-18019D01*
Y-17965D01*
Y-17911D01*
Y-17857D01*
Y-17803D01*
Y-17749D01*
Y-17695D01*
Y-17641D01*
Y-17587D01*
Y-17533D01*
Y-17479D01*
Y-17425D01*
Y-17371D01*
Y-17317D01*
Y-17263D01*
Y-17208D01*
Y-17154D01*
Y-17100D01*
Y-17046D01*
Y-16992D01*
Y-16938D01*
Y-16884D01*
Y-16830D01*
Y-16776D01*
Y-16722D01*
Y-16668D01*
Y-16614D01*
Y-16560D01*
Y-16506D01*
Y-16452D01*
Y-16398D01*
Y-16343D01*
Y-16289D01*
Y-16235D01*
Y-16181D01*
Y-16127D01*
Y-16073D01*
Y-16019D01*
Y-15965D01*
Y-15911D01*
Y-15857D01*
Y-15803D01*
Y-15749D01*
Y-15695D01*
Y-15641D01*
Y-15587D01*
Y-15532D01*
Y-15478D01*
Y-15424D01*
Y-15370D01*
Y-15316D01*
Y-15262D01*
Y-15208D01*
Y-15154D01*
Y-15100D01*
Y-15046D01*
Y-14992D01*
Y-14938D01*
Y-14884D01*
Y-14830D01*
Y-14776D01*
Y-14722D01*
Y-14668D01*
Y-14614D01*
Y-14559D01*
Y-14505D01*
Y-14451D01*
D02*
G37*
G36*
X359833Y-33643D02*
X359076D01*
Y-33697D01*
X358860D01*
Y-33751D01*
X358752D01*
Y-33806D01*
X358644D01*
Y-33860D01*
X358590D01*
Y-33914D01*
X358536D01*
Y-33968D01*
X358481D01*
Y-34022D01*
X358427D01*
Y-34076D01*
X358373D01*
Y-34130D01*
X358319D01*
Y-34184D01*
X358265D01*
Y-34238D01*
X358211D01*
Y-34292D01*
X358157D01*
Y-34346D01*
X358103D01*
Y-34400D01*
X358049D01*
Y-34454D01*
X357995D01*
Y-34508D01*
X357941D01*
Y-34562D01*
X357887D01*
Y-34616D01*
X357833D01*
Y-34670D01*
X357779D01*
Y-34725D01*
X357725D01*
Y-34779D01*
X357670D01*
Y-34833D01*
X357616D01*
Y-34887D01*
X357562D01*
Y-34941D01*
X357508D01*
Y-34995D01*
X357454D01*
Y-35049D01*
X357400D01*
Y-35103D01*
X357346D01*
Y-35157D01*
X357292D01*
Y-35211D01*
X357238D01*
Y-35265D01*
X357184D01*
Y-35319D01*
X357130D01*
Y-35373D01*
Y-35427D01*
Y-35481D01*
X357076D01*
Y-35535D01*
Y-35590D01*
Y-35644D01*
Y-35698D01*
X357022D01*
Y-35752D01*
Y-35806D01*
Y-35860D01*
Y-35914D01*
Y-35968D01*
Y-36022D01*
Y-36076D01*
Y-36130D01*
Y-36184D01*
Y-36238D01*
Y-36292D01*
Y-36346D01*
Y-36400D01*
Y-36454D01*
Y-36509D01*
Y-36563D01*
Y-36617D01*
Y-36671D01*
Y-36725D01*
Y-36779D01*
Y-36833D01*
Y-36887D01*
Y-36941D01*
Y-36995D01*
Y-37049D01*
Y-37103D01*
Y-37157D01*
Y-37211D01*
Y-37265D01*
Y-37319D01*
Y-37374D01*
Y-37428D01*
Y-37482D01*
Y-37536D01*
Y-37590D01*
Y-37644D01*
Y-37698D01*
Y-37752D01*
Y-37806D01*
Y-37860D01*
Y-37914D01*
Y-37968D01*
Y-38022D01*
Y-38076D01*
Y-38130D01*
Y-38184D01*
Y-38238D01*
Y-38293D01*
Y-38347D01*
Y-38401D01*
Y-38455D01*
Y-38509D01*
Y-38563D01*
Y-38617D01*
Y-38671D01*
Y-38725D01*
Y-38779D01*
Y-38833D01*
Y-38887D01*
Y-38941D01*
Y-38995D01*
Y-39050D01*
Y-39103D01*
Y-39158D01*
Y-39212D01*
Y-39266D01*
Y-39320D01*
Y-39374D01*
Y-39428D01*
Y-39482D01*
Y-39536D01*
Y-39590D01*
Y-39644D01*
Y-39698D01*
Y-39752D01*
Y-39806D01*
Y-39860D01*
Y-39915D01*
Y-39968D01*
Y-40023D01*
Y-40077D01*
Y-40131D01*
Y-40185D01*
Y-40239D01*
Y-40293D01*
Y-40347D01*
Y-40401D01*
Y-40455D01*
Y-40509D01*
Y-40563D01*
Y-40617D01*
Y-40671D01*
Y-40725D01*
Y-40780D01*
Y-40834D01*
Y-40888D01*
Y-40942D01*
Y-40996D01*
Y-41050D01*
Y-41104D01*
Y-41158D01*
Y-41212D01*
Y-41266D01*
Y-41320D01*
Y-41374D01*
Y-41428D01*
Y-41482D01*
Y-41536D01*
Y-41590D01*
Y-41644D01*
Y-41699D01*
Y-41753D01*
Y-41807D01*
Y-41861D01*
Y-41915D01*
Y-41969D01*
Y-42023D01*
Y-42077D01*
Y-42131D01*
Y-42185D01*
Y-42239D01*
Y-42293D01*
Y-42347D01*
Y-42401D01*
Y-42455D01*
Y-42509D01*
Y-42564D01*
Y-42618D01*
Y-42672D01*
Y-42726D01*
Y-42780D01*
Y-42834D01*
Y-42888D01*
Y-42942D01*
Y-42996D01*
Y-43050D01*
Y-43104D01*
Y-43158D01*
Y-43212D01*
Y-43266D01*
Y-43320D01*
Y-43374D01*
Y-43429D01*
Y-43483D01*
Y-43537D01*
Y-43591D01*
Y-43645D01*
Y-43699D01*
Y-43753D01*
Y-43807D01*
Y-43861D01*
Y-43915D01*
Y-43969D01*
Y-44023D01*
Y-44077D01*
Y-44131D01*
Y-44185D01*
Y-44239D01*
Y-44293D01*
Y-44348D01*
Y-44402D01*
Y-44456D01*
Y-44510D01*
Y-44564D01*
Y-44618D01*
Y-44672D01*
Y-44726D01*
Y-44780D01*
Y-44834D01*
Y-44888D01*
Y-44942D01*
Y-44996D01*
Y-45050D01*
Y-45104D01*
Y-45158D01*
Y-45213D01*
X357076D01*
Y-45267D01*
Y-45321D01*
X357130D01*
Y-45375D01*
X357238D01*
Y-45429D01*
X359779D01*
Y-45375D01*
X359887D01*
Y-45321D01*
X359941D01*
Y-45267D01*
X359995D01*
Y-45213D01*
Y-45158D01*
Y-45104D01*
Y-45050D01*
Y-44996D01*
Y-44942D01*
Y-44888D01*
Y-44834D01*
Y-44780D01*
Y-44726D01*
Y-44672D01*
Y-44618D01*
Y-44564D01*
Y-44510D01*
Y-44456D01*
Y-44402D01*
Y-44348D01*
Y-44293D01*
Y-44239D01*
Y-44185D01*
Y-44131D01*
Y-44077D01*
Y-44023D01*
Y-43969D01*
Y-43915D01*
Y-43861D01*
Y-43807D01*
Y-43753D01*
Y-43699D01*
Y-43645D01*
Y-43591D01*
Y-43537D01*
Y-43483D01*
Y-43429D01*
Y-43374D01*
Y-43320D01*
Y-43266D01*
Y-43212D01*
Y-43158D01*
Y-43104D01*
Y-43050D01*
Y-42996D01*
Y-42942D01*
Y-42888D01*
Y-42834D01*
Y-42780D01*
Y-42726D01*
Y-42672D01*
Y-42618D01*
Y-42564D01*
Y-42509D01*
Y-42455D01*
Y-42401D01*
Y-42347D01*
Y-42293D01*
Y-42239D01*
Y-42185D01*
Y-42131D01*
Y-42077D01*
Y-42023D01*
Y-41969D01*
X360049D01*
Y-41915D01*
Y-41861D01*
X360157D01*
Y-41807D01*
X363779D01*
Y-41861D01*
X363888D01*
Y-41915D01*
Y-41969D01*
X363942D01*
Y-42023D01*
Y-42077D01*
Y-42131D01*
Y-42185D01*
Y-42239D01*
Y-42293D01*
Y-42347D01*
Y-42401D01*
Y-42455D01*
Y-42509D01*
Y-42564D01*
Y-42618D01*
Y-42672D01*
Y-42726D01*
Y-42780D01*
Y-42834D01*
Y-42888D01*
Y-42942D01*
Y-42996D01*
Y-43050D01*
Y-43104D01*
Y-43158D01*
Y-43212D01*
Y-43266D01*
Y-43320D01*
Y-43374D01*
Y-43429D01*
Y-43483D01*
Y-43537D01*
Y-43591D01*
Y-43645D01*
Y-43699D01*
Y-43753D01*
Y-43807D01*
Y-43861D01*
Y-43915D01*
Y-43969D01*
Y-44023D01*
Y-44077D01*
Y-44131D01*
Y-44185D01*
Y-44239D01*
Y-44293D01*
Y-44348D01*
Y-44402D01*
Y-44456D01*
Y-44510D01*
Y-44564D01*
Y-44618D01*
Y-44672D01*
Y-44726D01*
Y-44780D01*
Y-44834D01*
Y-44888D01*
Y-44942D01*
Y-44996D01*
Y-45050D01*
Y-45104D01*
Y-45158D01*
Y-45213D01*
X363996D01*
Y-45267D01*
Y-45321D01*
X364050D01*
Y-45375D01*
X364158D01*
Y-45429D01*
X366699D01*
Y-45375D01*
X366807D01*
Y-45321D01*
X366861D01*
Y-45267D01*
X366915D01*
Y-45213D01*
Y-45158D01*
Y-45104D01*
Y-45050D01*
Y-44996D01*
Y-44942D01*
Y-44888D01*
Y-44834D01*
Y-44780D01*
Y-44726D01*
Y-44672D01*
Y-44618D01*
Y-44564D01*
Y-44510D01*
Y-44456D01*
Y-44402D01*
Y-44348D01*
Y-44293D01*
Y-44239D01*
Y-44185D01*
Y-44131D01*
Y-44077D01*
Y-44023D01*
Y-43969D01*
Y-43915D01*
Y-43861D01*
Y-43807D01*
Y-43753D01*
Y-43699D01*
Y-43645D01*
Y-43591D01*
Y-43537D01*
Y-43483D01*
Y-43429D01*
Y-43374D01*
Y-43320D01*
Y-43266D01*
Y-43212D01*
Y-43158D01*
Y-43104D01*
Y-43050D01*
Y-42996D01*
Y-42942D01*
Y-42888D01*
Y-42834D01*
Y-42780D01*
Y-42726D01*
Y-42672D01*
Y-42618D01*
Y-42564D01*
Y-42509D01*
Y-42455D01*
Y-42401D01*
Y-42347D01*
Y-42293D01*
Y-42239D01*
Y-42185D01*
Y-42131D01*
Y-42077D01*
Y-42023D01*
Y-41969D01*
Y-41915D01*
Y-41861D01*
Y-41807D01*
Y-41753D01*
Y-41699D01*
Y-41644D01*
Y-41590D01*
Y-41536D01*
Y-41482D01*
Y-41428D01*
Y-41374D01*
Y-41320D01*
Y-41266D01*
Y-41212D01*
Y-41158D01*
Y-41104D01*
Y-41050D01*
Y-40996D01*
Y-40942D01*
X366861D01*
Y-40888D01*
X366807D01*
Y-40834D01*
X366753D01*
Y-40780D01*
X366699D01*
Y-40725D01*
X366645D01*
Y-40671D01*
X366591D01*
Y-40617D01*
X366483D01*
Y-40563D01*
X366429D01*
Y-40509D01*
X366374D01*
Y-40455D01*
X366320D01*
Y-40401D01*
X366266D01*
Y-40347D01*
X366212D01*
Y-40293D01*
X366158D01*
Y-40239D01*
X366104D01*
Y-40185D01*
X366050D01*
Y-40131D01*
X365996D01*
Y-40077D01*
X365942D01*
Y-40023D01*
X365888D01*
Y-39968D01*
X365834D01*
Y-39915D01*
X365780D01*
Y-39860D01*
X365726D01*
Y-39806D01*
X365672D01*
Y-39752D01*
X365618D01*
Y-39698D01*
X365564D01*
Y-39644D01*
X365510D01*
Y-39590D01*
X365456D01*
Y-39536D01*
X365401D01*
Y-39482D01*
X365347D01*
Y-39428D01*
X365293D01*
Y-39374D01*
X365239D01*
Y-39320D01*
X365185D01*
Y-39266D01*
X365131D01*
Y-39212D01*
X365077D01*
Y-39158D01*
X365023D01*
Y-39103D01*
X364969D01*
Y-39050D01*
X364915D01*
Y-38995D01*
X364861D01*
Y-38941D01*
X364807D01*
Y-38887D01*
X364753D01*
Y-38833D01*
X364699D01*
Y-38779D01*
X364645D01*
Y-38725D01*
X364591D01*
Y-38671D01*
X364536D01*
Y-38617D01*
X364482D01*
Y-38563D01*
X364428D01*
Y-38509D01*
X364374D01*
Y-38455D01*
X364320D01*
Y-38401D01*
X364266D01*
Y-38347D01*
X364212D01*
Y-38293D01*
X364158D01*
Y-38238D01*
X364104D01*
Y-38184D01*
X364050D01*
Y-38130D01*
X363996D01*
Y-38076D01*
X363942D01*
Y-38130D01*
Y-38184D01*
Y-38238D01*
Y-38293D01*
Y-38347D01*
Y-38401D01*
Y-38455D01*
Y-38509D01*
Y-38563D01*
Y-38617D01*
Y-38671D01*
Y-38725D01*
Y-38779D01*
Y-38833D01*
Y-38887D01*
Y-38941D01*
Y-38995D01*
Y-39050D01*
Y-39103D01*
Y-39158D01*
Y-39212D01*
Y-39266D01*
X359995D01*
Y-39212D01*
Y-39158D01*
Y-39103D01*
Y-39050D01*
Y-38995D01*
Y-38941D01*
Y-38887D01*
Y-38833D01*
Y-38779D01*
Y-38725D01*
Y-38671D01*
Y-38617D01*
Y-38563D01*
Y-38509D01*
Y-38455D01*
Y-38401D01*
Y-38347D01*
Y-38293D01*
Y-38238D01*
Y-38184D01*
Y-38130D01*
Y-38076D01*
Y-38022D01*
Y-37968D01*
Y-37914D01*
Y-37860D01*
Y-37806D01*
Y-37752D01*
Y-37698D01*
Y-37644D01*
Y-37590D01*
Y-37536D01*
Y-37482D01*
Y-37428D01*
Y-37374D01*
Y-37319D01*
Y-37265D01*
Y-37211D01*
Y-37157D01*
Y-37103D01*
Y-37049D01*
Y-36995D01*
Y-36941D01*
Y-36887D01*
Y-36833D01*
Y-36779D01*
Y-36725D01*
Y-36671D01*
Y-36617D01*
Y-36563D01*
Y-36509D01*
Y-36454D01*
Y-36400D01*
Y-36346D01*
Y-36292D01*
X362428D01*
Y-36238D01*
X362374D01*
Y-36184D01*
X362320D01*
Y-36130D01*
X362266D01*
Y-36076D01*
X362212D01*
Y-36022D01*
X362158D01*
Y-35968D01*
X362104D01*
Y-35914D01*
X362050D01*
Y-35860D01*
X361996D01*
Y-35806D01*
X361941D01*
Y-35752D01*
X361887D01*
Y-35698D01*
X361833D01*
Y-35644D01*
X361779D01*
Y-35590D01*
X361725D01*
Y-35535D01*
X361671D01*
Y-35481D01*
X361617D01*
Y-35427D01*
X361563D01*
Y-35373D01*
X361509D01*
Y-35319D01*
X361455D01*
Y-35265D01*
X361401D01*
Y-35211D01*
X361347D01*
Y-35157D01*
X361293D01*
Y-35103D01*
X361239D01*
Y-35049D01*
X361185D01*
Y-34995D01*
X361130D01*
Y-34941D01*
X361076D01*
Y-34887D01*
X361022D01*
Y-34833D01*
X360968D01*
Y-34779D01*
X360914D01*
Y-34725D01*
X360860D01*
Y-34670D01*
X360806D01*
Y-34616D01*
X360752D01*
Y-34562D01*
X360698D01*
Y-34508D01*
X360644D01*
Y-34454D01*
X360590D01*
Y-34400D01*
X360536D01*
Y-34346D01*
X360482D01*
Y-34292D01*
X360428D01*
Y-34238D01*
X360374D01*
Y-34184D01*
X360320D01*
Y-34130D01*
X360265D01*
Y-34076D01*
X360211D01*
Y-34022D01*
X360157D01*
Y-33968D01*
X360103D01*
Y-33914D01*
X360049D01*
Y-33860D01*
X359995D01*
Y-33806D01*
X359941D01*
Y-33751D01*
X359887D01*
Y-33697D01*
X359833D01*
Y-33643D01*
D02*
G37*
G36*
X355616D02*
X348156D01*
Y-33697D01*
X347885D01*
Y-33751D01*
X347723D01*
Y-33806D01*
X347615D01*
Y-33860D01*
X347561D01*
Y-33914D01*
X347507D01*
Y-33968D01*
X347453D01*
Y-34022D01*
X347399D01*
Y-34076D01*
X347345D01*
Y-34130D01*
X347291D01*
Y-34184D01*
X347236D01*
Y-34238D01*
X347182D01*
Y-34292D01*
X347128D01*
Y-34346D01*
X347074D01*
Y-34400D01*
X347020D01*
Y-34454D01*
X346966D01*
Y-34508D01*
X346912D01*
Y-34562D01*
X346858D01*
Y-34616D01*
X346804D01*
Y-34670D01*
X346750D01*
Y-34725D01*
X346696D01*
Y-34779D01*
X346642D01*
Y-34833D01*
X346588D01*
Y-34887D01*
X346534D01*
Y-34941D01*
X346480D01*
Y-34995D01*
X346426D01*
Y-35049D01*
X346372D01*
Y-35103D01*
X346318D01*
Y-35157D01*
X346263D01*
Y-35211D01*
X346209D01*
Y-35265D01*
X346155D01*
Y-35319D01*
X346101D01*
Y-35373D01*
Y-35427D01*
X346047D01*
Y-35481D01*
Y-35535D01*
Y-35590D01*
X345993D01*
Y-35644D01*
Y-35698D01*
Y-35752D01*
Y-35806D01*
Y-35860D01*
Y-35914D01*
Y-35968D01*
Y-36022D01*
Y-36076D01*
Y-36130D01*
Y-36184D01*
Y-36238D01*
Y-36292D01*
Y-36346D01*
Y-36400D01*
Y-36454D01*
Y-36509D01*
Y-36563D01*
Y-36617D01*
Y-36671D01*
Y-36725D01*
Y-36779D01*
Y-36833D01*
Y-36887D01*
Y-36941D01*
Y-36995D01*
Y-37049D01*
Y-37103D01*
Y-37157D01*
Y-37211D01*
Y-37265D01*
Y-37319D01*
Y-37374D01*
Y-37428D01*
Y-37482D01*
Y-37536D01*
Y-37590D01*
Y-37644D01*
Y-37698D01*
Y-37752D01*
Y-37806D01*
Y-37860D01*
Y-37914D01*
Y-37968D01*
Y-38022D01*
Y-38076D01*
Y-38130D01*
Y-38184D01*
Y-38238D01*
Y-38293D01*
Y-38347D01*
Y-38401D01*
Y-38455D01*
Y-38509D01*
Y-38563D01*
Y-38617D01*
Y-38671D01*
Y-38725D01*
Y-38779D01*
Y-38833D01*
Y-38887D01*
Y-38941D01*
Y-38995D01*
Y-39050D01*
Y-39103D01*
Y-39158D01*
Y-39212D01*
Y-39266D01*
Y-39320D01*
Y-39374D01*
Y-39428D01*
Y-39482D01*
Y-39536D01*
Y-39590D01*
Y-39644D01*
Y-39698D01*
Y-39752D01*
Y-39806D01*
Y-39860D01*
X346047D01*
Y-39915D01*
Y-39968D01*
X346101D01*
Y-40023D01*
Y-40077D01*
X346155D01*
Y-40131D01*
X346209D01*
Y-40185D01*
X346263D01*
Y-40239D01*
X346318D01*
Y-40293D01*
X346372D01*
Y-40347D01*
X346426D01*
Y-40401D01*
Y-40455D01*
X346480D01*
Y-40509D01*
X346534D01*
Y-40563D01*
X346588D01*
Y-40617D01*
X346642D01*
Y-40671D01*
X346696D01*
Y-40725D01*
X346750D01*
Y-40780D01*
X346804D01*
Y-40834D01*
X346858D01*
Y-40888D01*
X346912D01*
Y-40942D01*
X346966D01*
Y-40996D01*
X347020D01*
Y-41050D01*
X347074D01*
Y-41104D01*
X347128D01*
Y-41158D01*
X347182D01*
Y-41212D01*
X347236D01*
Y-41266D01*
X347291D01*
Y-41320D01*
X347345D01*
Y-41374D01*
X347399D01*
Y-41428D01*
X347453D01*
Y-41482D01*
X347507D01*
Y-41536D01*
X347561D01*
Y-41590D01*
X347615D01*
Y-41644D01*
X347669D01*
Y-41699D01*
Y-41753D01*
X347615D01*
Y-41807D01*
X347561D01*
Y-41861D01*
Y-41915D01*
X347507D01*
Y-41969D01*
Y-42023D01*
X347453D01*
Y-42077D01*
X347399D01*
Y-42131D01*
Y-42185D01*
X347345D01*
Y-42239D01*
Y-42293D01*
X347291D01*
Y-42347D01*
Y-42401D01*
X347236D01*
Y-42455D01*
X347182D01*
Y-42509D01*
Y-42564D01*
X347128D01*
Y-42618D01*
Y-42672D01*
X347074D01*
Y-42726D01*
X347020D01*
Y-42780D01*
Y-42834D01*
X346966D01*
Y-42888D01*
Y-42942D01*
X346912D01*
Y-42996D01*
X346858D01*
Y-43050D01*
Y-43104D01*
X346804D01*
Y-43158D01*
Y-43212D01*
X346750D01*
Y-43266D01*
X346696D01*
Y-43320D01*
Y-43374D01*
X346642D01*
Y-43429D01*
Y-43483D01*
X346588D01*
Y-43537D01*
X346534D01*
Y-43591D01*
Y-43645D01*
X346480D01*
Y-43699D01*
Y-43753D01*
X346426D01*
Y-43807D01*
X346372D01*
Y-43861D01*
Y-43915D01*
X346318D01*
Y-43969D01*
Y-44023D01*
X346263D01*
Y-44077D01*
X346209D01*
Y-44131D01*
Y-44185D01*
X346155D01*
Y-44239D01*
Y-44293D01*
X346101D01*
Y-44348D01*
X346047D01*
Y-44402D01*
Y-44456D01*
X345993D01*
Y-44510D01*
Y-44564D01*
X345939D01*
Y-44618D01*
X345885D01*
Y-44672D01*
Y-44726D01*
X345831D01*
Y-44780D01*
Y-44834D01*
X345777D01*
Y-44888D01*
X345723D01*
Y-44942D01*
Y-44996D01*
X345669D01*
Y-45050D01*
Y-45104D01*
X345615D01*
Y-45158D01*
X345561D01*
Y-45213D01*
Y-45267D01*
Y-45321D01*
Y-45375D01*
X345615D01*
Y-45429D01*
X348642D01*
Y-45375D01*
X348750D01*
Y-45321D01*
X348804D01*
Y-45267D01*
X348858D01*
Y-45213D01*
X348913D01*
Y-45158D01*
X348967D01*
Y-45104D01*
Y-45050D01*
X349021D01*
Y-44996D01*
Y-44942D01*
X349075D01*
Y-44888D01*
X349129D01*
Y-44834D01*
Y-44780D01*
X349183D01*
Y-44726D01*
Y-44672D01*
X349237D01*
Y-44618D01*
Y-44564D01*
X349291D01*
Y-44510D01*
X349345D01*
Y-44456D01*
Y-44402D01*
X349399D01*
Y-44348D01*
Y-44293D01*
X349453D01*
Y-44239D01*
X349507D01*
Y-44185D01*
Y-44131D01*
X349561D01*
Y-44077D01*
Y-44023D01*
X349615D01*
Y-43969D01*
X349669D01*
Y-43915D01*
Y-43861D01*
X349723D01*
Y-43807D01*
Y-43753D01*
X349778D01*
Y-43699D01*
X349832D01*
Y-43645D01*
Y-43591D01*
X349886D01*
Y-43537D01*
Y-43483D01*
X349940D01*
Y-43429D01*
Y-43374D01*
X349994D01*
Y-43320D01*
X350048D01*
Y-43266D01*
Y-43212D01*
X350102D01*
Y-43158D01*
Y-43104D01*
X350156D01*
Y-43050D01*
X350210D01*
Y-42996D01*
Y-42942D01*
X350264D01*
Y-42888D01*
Y-42834D01*
X350318D01*
Y-42780D01*
X350372D01*
Y-42726D01*
Y-42672D01*
X350426D01*
Y-42618D01*
Y-42564D01*
X350480D01*
Y-42509D01*
Y-42455D01*
X350534D01*
Y-42401D01*
X350588D01*
Y-42347D01*
Y-42293D01*
X350642D01*
Y-42239D01*
Y-42185D01*
X350696D01*
Y-42131D01*
X350751D01*
Y-42077D01*
Y-42023D01*
X350805D01*
Y-41969D01*
Y-41915D01*
X352859D01*
Y-41969D01*
Y-42023D01*
Y-42077D01*
Y-42131D01*
Y-42185D01*
X352913D01*
Y-42239D01*
X352859D01*
Y-42293D01*
Y-42347D01*
Y-42401D01*
Y-42455D01*
Y-42509D01*
Y-42564D01*
Y-42618D01*
Y-42672D01*
Y-42726D01*
Y-42780D01*
Y-42834D01*
Y-42888D01*
Y-42942D01*
Y-42996D01*
Y-43050D01*
Y-43104D01*
Y-43158D01*
Y-43212D01*
Y-43266D01*
Y-43320D01*
Y-43374D01*
Y-43429D01*
Y-43483D01*
Y-43537D01*
Y-43591D01*
Y-43645D01*
Y-43699D01*
Y-43753D01*
Y-43807D01*
Y-43861D01*
Y-43915D01*
Y-43969D01*
Y-44023D01*
Y-44077D01*
Y-44131D01*
Y-44185D01*
Y-44239D01*
Y-44293D01*
Y-44348D01*
Y-44402D01*
Y-44456D01*
Y-44510D01*
Y-44564D01*
Y-44618D01*
Y-44672D01*
Y-44726D01*
Y-44780D01*
Y-44834D01*
Y-44888D01*
Y-44942D01*
Y-44996D01*
Y-45050D01*
Y-45104D01*
Y-45158D01*
X352913D01*
Y-45213D01*
Y-45267D01*
Y-45321D01*
X352967D01*
Y-45375D01*
X353021D01*
Y-45429D01*
X355670D01*
Y-45375D01*
X355778D01*
Y-45321D01*
X355832D01*
Y-45267D01*
Y-45213D01*
Y-45158D01*
X355887D01*
Y-45104D01*
X355832D01*
Y-45050D01*
X355887D01*
Y-44996D01*
Y-44942D01*
Y-44888D01*
Y-44834D01*
Y-44780D01*
Y-44726D01*
Y-44672D01*
Y-44618D01*
Y-44564D01*
Y-44510D01*
Y-44456D01*
Y-44402D01*
Y-44348D01*
Y-44293D01*
Y-44239D01*
Y-44185D01*
Y-44131D01*
Y-44077D01*
Y-44023D01*
Y-43969D01*
Y-43915D01*
Y-43861D01*
Y-43807D01*
Y-43753D01*
Y-43699D01*
Y-43645D01*
Y-43591D01*
Y-43537D01*
Y-43483D01*
Y-43429D01*
Y-43374D01*
Y-43320D01*
Y-43266D01*
Y-43212D01*
Y-43158D01*
Y-43104D01*
Y-43050D01*
Y-42996D01*
Y-42942D01*
Y-42888D01*
Y-42834D01*
Y-42780D01*
Y-42726D01*
Y-42672D01*
Y-42618D01*
Y-42564D01*
Y-42509D01*
Y-42455D01*
Y-42401D01*
Y-42347D01*
Y-42293D01*
Y-42239D01*
Y-42185D01*
Y-42131D01*
Y-42077D01*
Y-42023D01*
Y-41969D01*
Y-41915D01*
Y-41861D01*
Y-41807D01*
Y-41753D01*
Y-41699D01*
Y-41644D01*
Y-41590D01*
Y-41536D01*
Y-41482D01*
Y-41428D01*
Y-41374D01*
Y-41320D01*
Y-41266D01*
Y-41212D01*
Y-41158D01*
Y-41104D01*
Y-41050D01*
Y-40996D01*
Y-40942D01*
Y-40888D01*
Y-40834D01*
Y-40780D01*
Y-40725D01*
Y-40671D01*
Y-40617D01*
Y-40563D01*
Y-40509D01*
Y-40455D01*
Y-40401D01*
Y-40347D01*
Y-40293D01*
Y-40239D01*
Y-40185D01*
Y-40131D01*
Y-40077D01*
Y-40023D01*
Y-39968D01*
Y-39915D01*
Y-39860D01*
Y-39806D01*
Y-39752D01*
Y-39698D01*
Y-39644D01*
Y-39590D01*
Y-39536D01*
Y-39482D01*
Y-39428D01*
Y-39374D01*
Y-39320D01*
Y-39266D01*
Y-39212D01*
Y-39158D01*
Y-39103D01*
Y-39050D01*
Y-38995D01*
Y-38941D01*
Y-38887D01*
Y-38833D01*
Y-38779D01*
Y-38725D01*
Y-38671D01*
Y-38617D01*
Y-38563D01*
Y-38509D01*
Y-38455D01*
Y-38401D01*
Y-38347D01*
Y-38293D01*
Y-38238D01*
Y-38184D01*
Y-38130D01*
Y-38076D01*
Y-38022D01*
Y-37968D01*
Y-37914D01*
Y-37860D01*
Y-37806D01*
Y-37752D01*
Y-37698D01*
Y-37644D01*
Y-37590D01*
Y-37536D01*
Y-37482D01*
Y-37428D01*
Y-37374D01*
Y-37319D01*
Y-37265D01*
Y-37211D01*
Y-37157D01*
Y-37103D01*
Y-37049D01*
Y-36995D01*
Y-36941D01*
Y-36887D01*
Y-36833D01*
Y-36779D01*
Y-36725D01*
Y-36671D01*
Y-36617D01*
Y-36563D01*
Y-36509D01*
Y-36454D01*
Y-36400D01*
Y-36346D01*
Y-36292D01*
Y-36238D01*
Y-36184D01*
Y-36130D01*
Y-36076D01*
Y-36022D01*
Y-35968D01*
Y-35914D01*
Y-35860D01*
Y-35806D01*
Y-35752D01*
Y-35698D01*
Y-35644D01*
Y-35590D01*
Y-35535D01*
Y-35481D01*
Y-35427D01*
Y-35373D01*
Y-35319D01*
Y-35265D01*
Y-35211D01*
Y-35157D01*
Y-35103D01*
Y-35049D01*
Y-34995D01*
Y-34941D01*
Y-34887D01*
Y-34833D01*
Y-34779D01*
Y-34725D01*
Y-34670D01*
Y-34616D01*
Y-34562D01*
Y-34508D01*
Y-34454D01*
Y-34400D01*
Y-34346D01*
Y-34292D01*
Y-34238D01*
Y-34184D01*
Y-34130D01*
Y-34076D01*
Y-34022D01*
Y-33968D01*
X355832D01*
Y-33914D01*
Y-33860D01*
Y-33806D01*
X355778D01*
Y-33751D01*
X355724D01*
Y-33697D01*
X355616D01*
Y-33643D01*
D02*
G37*
G36*
X344101D02*
X336640D01*
Y-33697D01*
X336370D01*
Y-33751D01*
X336208D01*
Y-33806D01*
X336154D01*
Y-33860D01*
X336100D01*
Y-33914D01*
X336046D01*
Y-33968D01*
X335992D01*
Y-34022D01*
X335938D01*
Y-34076D01*
X335883D01*
Y-34130D01*
X335829D01*
Y-34184D01*
X335775D01*
Y-34238D01*
X335721D01*
Y-34292D01*
X335667D01*
Y-34346D01*
X335613D01*
Y-34400D01*
X335559D01*
Y-34454D01*
X335505D01*
Y-34508D01*
X335451D01*
Y-34562D01*
X335397D01*
Y-34616D01*
X335343D01*
Y-34670D01*
X335289D01*
Y-34725D01*
X335235D01*
Y-34779D01*
X335181D01*
Y-34833D01*
X335127D01*
Y-34887D01*
X335073D01*
Y-34941D01*
X335018D01*
Y-34995D01*
X334964D01*
Y-35049D01*
X334910D01*
Y-35103D01*
X334856D01*
Y-35157D01*
X334802D01*
Y-35211D01*
X334748D01*
Y-35265D01*
X334694D01*
Y-35319D01*
X334640D01*
Y-35373D01*
X334586D01*
Y-35427D01*
Y-35481D01*
X334532D01*
Y-35535D01*
Y-35590D01*
Y-35644D01*
Y-35698D01*
X334478D01*
Y-35752D01*
Y-35806D01*
Y-35860D01*
Y-35914D01*
Y-35968D01*
Y-36022D01*
Y-36076D01*
Y-36130D01*
Y-36184D01*
Y-36238D01*
Y-36292D01*
Y-36346D01*
Y-36400D01*
Y-36454D01*
Y-36509D01*
Y-36563D01*
Y-36617D01*
Y-36671D01*
Y-36725D01*
Y-36779D01*
Y-36833D01*
Y-36887D01*
Y-36941D01*
Y-36995D01*
Y-37049D01*
Y-37103D01*
Y-37157D01*
Y-37211D01*
Y-37265D01*
Y-37319D01*
Y-37374D01*
Y-37428D01*
Y-37482D01*
Y-37536D01*
Y-37590D01*
Y-37644D01*
Y-37698D01*
Y-37752D01*
Y-37806D01*
Y-37860D01*
Y-37914D01*
Y-37968D01*
Y-38022D01*
Y-38076D01*
Y-38130D01*
Y-38184D01*
Y-38238D01*
Y-38293D01*
Y-38347D01*
Y-38401D01*
Y-38455D01*
Y-38509D01*
Y-38563D01*
Y-38617D01*
Y-38671D01*
Y-38725D01*
Y-38779D01*
Y-38833D01*
Y-38887D01*
Y-38941D01*
Y-38995D01*
Y-39050D01*
Y-39103D01*
Y-39158D01*
Y-39212D01*
Y-39266D01*
Y-39320D01*
Y-39374D01*
Y-39428D01*
Y-39482D01*
Y-39536D01*
Y-39590D01*
Y-39644D01*
Y-39698D01*
Y-39752D01*
Y-39806D01*
Y-39860D01*
Y-39915D01*
Y-39968D01*
Y-40023D01*
Y-40077D01*
Y-40131D01*
Y-40185D01*
Y-40239D01*
Y-40293D01*
Y-40347D01*
Y-40401D01*
Y-40455D01*
Y-40509D01*
Y-40563D01*
Y-40617D01*
Y-40671D01*
Y-40725D01*
Y-40780D01*
Y-40834D01*
Y-40888D01*
Y-40942D01*
Y-40996D01*
Y-41050D01*
Y-41104D01*
Y-41158D01*
Y-41212D01*
Y-41266D01*
Y-41320D01*
Y-41374D01*
Y-41428D01*
Y-41482D01*
Y-41536D01*
Y-41590D01*
Y-41644D01*
Y-41699D01*
Y-41753D01*
Y-41807D01*
Y-41861D01*
Y-41915D01*
Y-41969D01*
Y-42023D01*
Y-42077D01*
Y-42131D01*
Y-42185D01*
Y-42239D01*
Y-42293D01*
Y-42347D01*
Y-42401D01*
Y-42455D01*
Y-42509D01*
Y-42564D01*
Y-42618D01*
Y-42672D01*
Y-42726D01*
Y-42780D01*
Y-42834D01*
Y-42888D01*
Y-42942D01*
Y-42996D01*
Y-43050D01*
Y-43104D01*
Y-43158D01*
Y-43212D01*
Y-43266D01*
Y-43320D01*
Y-43374D01*
X334532D01*
Y-43429D01*
Y-43483D01*
Y-43537D01*
Y-43591D01*
X334586D01*
Y-43645D01*
Y-43699D01*
Y-43753D01*
X334640D01*
Y-43807D01*
X334694D01*
Y-43861D01*
X334748D01*
Y-43915D01*
X334802D01*
Y-43969D01*
X334856D01*
Y-44023D01*
X334910D01*
Y-44077D01*
X334964D01*
Y-44131D01*
X335018D01*
Y-44185D01*
X335073D01*
Y-44239D01*
X335127D01*
Y-44293D01*
X335181D01*
Y-44348D01*
X335235D01*
Y-44402D01*
X335289D01*
Y-44456D01*
X335343D01*
Y-44510D01*
X335397D01*
Y-44564D01*
X335451D01*
Y-44618D01*
X335505D01*
Y-44672D01*
X335559D01*
Y-44726D01*
X335613D01*
Y-44780D01*
X335667D01*
Y-44834D01*
X335721D01*
Y-44888D01*
X335775D01*
Y-44942D01*
X335829D01*
Y-44996D01*
X335883D01*
Y-45050D01*
X335938D01*
Y-45104D01*
X335992D01*
Y-45158D01*
X336046D01*
Y-45213D01*
X336100D01*
Y-45267D01*
X336154D01*
Y-45321D01*
X336262D01*
Y-45375D01*
X336478D01*
Y-45429D01*
X344209D01*
Y-45375D01*
X344263D01*
Y-45321D01*
X344317D01*
Y-45267D01*
X344371D01*
Y-45213D01*
Y-45158D01*
Y-45104D01*
Y-45050D01*
Y-44996D01*
Y-44942D01*
Y-44888D01*
Y-44834D01*
Y-44780D01*
Y-44726D01*
Y-44672D01*
Y-44618D01*
Y-44564D01*
Y-44510D01*
Y-44456D01*
Y-44402D01*
Y-44348D01*
Y-44293D01*
Y-44239D01*
Y-44185D01*
Y-44131D01*
Y-44077D01*
Y-44023D01*
Y-43969D01*
Y-43915D01*
Y-43861D01*
Y-43807D01*
Y-43753D01*
Y-43699D01*
Y-43645D01*
Y-43591D01*
Y-43537D01*
Y-43483D01*
Y-43429D01*
Y-43374D01*
Y-43320D01*
Y-43266D01*
Y-43212D01*
Y-43158D01*
Y-43104D01*
Y-43050D01*
Y-42996D01*
Y-42942D01*
Y-42888D01*
Y-42834D01*
Y-42780D01*
Y-42726D01*
Y-42672D01*
Y-42618D01*
Y-42564D01*
Y-42509D01*
Y-42455D01*
Y-42401D01*
Y-42347D01*
Y-42293D01*
Y-42239D01*
Y-42185D01*
Y-42131D01*
Y-42077D01*
Y-42023D01*
Y-41969D01*
Y-41915D01*
Y-41861D01*
Y-41807D01*
Y-41753D01*
Y-41699D01*
Y-41644D01*
Y-41590D01*
Y-41536D01*
Y-41482D01*
Y-41428D01*
Y-41374D01*
Y-41320D01*
Y-41266D01*
Y-41212D01*
Y-41158D01*
Y-41104D01*
Y-41050D01*
Y-40996D01*
Y-40942D01*
Y-40888D01*
Y-40834D01*
Y-40780D01*
Y-40725D01*
Y-40671D01*
Y-40617D01*
Y-40563D01*
Y-40509D01*
Y-40455D01*
Y-40401D01*
Y-40347D01*
Y-40293D01*
Y-40239D01*
Y-40185D01*
Y-40131D01*
Y-40077D01*
Y-40023D01*
Y-39968D01*
Y-39915D01*
Y-39860D01*
Y-39806D01*
Y-39752D01*
Y-39698D01*
Y-39644D01*
Y-39590D01*
Y-39536D01*
Y-39482D01*
Y-39428D01*
Y-39374D01*
Y-39320D01*
Y-39266D01*
Y-39212D01*
Y-39158D01*
Y-39103D01*
Y-39050D01*
Y-38995D01*
Y-38941D01*
Y-38887D01*
Y-38833D01*
Y-38779D01*
Y-38725D01*
Y-38671D01*
Y-38617D01*
Y-38563D01*
Y-38509D01*
Y-38455D01*
Y-38401D01*
Y-38347D01*
Y-38293D01*
Y-38238D01*
Y-38184D01*
Y-38130D01*
Y-38076D01*
Y-38022D01*
Y-37968D01*
Y-37914D01*
Y-37860D01*
Y-37806D01*
Y-37752D01*
Y-37698D01*
Y-37644D01*
Y-37590D01*
Y-37536D01*
Y-37482D01*
Y-37428D01*
Y-37374D01*
Y-37319D01*
Y-37265D01*
Y-37211D01*
Y-37157D01*
Y-37103D01*
Y-37049D01*
Y-36995D01*
Y-36941D01*
Y-36887D01*
Y-36833D01*
Y-36779D01*
Y-36725D01*
Y-36671D01*
Y-36617D01*
Y-36563D01*
Y-36509D01*
Y-36454D01*
Y-36400D01*
Y-36346D01*
Y-36292D01*
Y-36238D01*
Y-36184D01*
Y-36130D01*
Y-36076D01*
Y-36022D01*
Y-35968D01*
Y-35914D01*
Y-35860D01*
Y-35806D01*
Y-35752D01*
Y-35698D01*
Y-35644D01*
Y-35590D01*
Y-35535D01*
Y-35481D01*
Y-35427D01*
Y-35373D01*
Y-35319D01*
Y-35265D01*
Y-35211D01*
Y-35157D01*
Y-35103D01*
Y-35049D01*
Y-34995D01*
Y-34941D01*
Y-34887D01*
Y-34833D01*
Y-34779D01*
Y-34725D01*
Y-34670D01*
Y-34616D01*
Y-34562D01*
Y-34508D01*
Y-34454D01*
Y-34400D01*
Y-34346D01*
Y-34292D01*
Y-34238D01*
Y-34184D01*
Y-34130D01*
Y-34076D01*
Y-34022D01*
Y-33968D01*
Y-33914D01*
Y-33860D01*
X344317D01*
Y-33806D01*
X344263D01*
Y-33751D01*
X344209D01*
Y-33697D01*
X344101D01*
Y-33643D01*
D02*
G37*
G36*
X382863Y-33697D02*
X382215D01*
Y-33751D01*
Y-33806D01*
Y-33860D01*
Y-33914D01*
Y-33968D01*
Y-34022D01*
X382161D01*
Y-34076D01*
Y-34130D01*
Y-34184D01*
Y-34238D01*
Y-34292D01*
Y-34346D01*
Y-34400D01*
Y-34454D01*
Y-34508D01*
Y-34562D01*
Y-34616D01*
Y-34670D01*
Y-34725D01*
Y-34779D01*
Y-34833D01*
Y-34887D01*
X382107D01*
Y-34941D01*
Y-34995D01*
Y-35049D01*
Y-35103D01*
Y-35157D01*
Y-35211D01*
Y-35265D01*
Y-35319D01*
Y-35373D01*
Y-35427D01*
X382052D01*
Y-35481D01*
Y-35535D01*
Y-35590D01*
Y-35644D01*
Y-35698D01*
Y-35752D01*
Y-35806D01*
Y-35860D01*
X381998D01*
Y-35914D01*
Y-35968D01*
Y-36022D01*
Y-36076D01*
Y-36130D01*
Y-36184D01*
Y-36238D01*
X381944D01*
Y-36292D01*
Y-36346D01*
Y-36400D01*
Y-36454D01*
Y-36509D01*
Y-36563D01*
X381890D01*
Y-36617D01*
Y-36671D01*
Y-36725D01*
Y-36779D01*
Y-36833D01*
X381836D01*
Y-36887D01*
Y-36941D01*
Y-36995D01*
Y-37049D01*
Y-37103D01*
X381782D01*
Y-37157D01*
Y-37211D01*
Y-37265D01*
Y-37319D01*
Y-37374D01*
X381728D01*
Y-37428D01*
Y-37482D01*
Y-37536D01*
Y-37590D01*
Y-37644D01*
X381674D01*
Y-37698D01*
Y-37752D01*
Y-37806D01*
Y-37860D01*
X381620D01*
Y-37914D01*
Y-37968D01*
Y-38022D01*
Y-38076D01*
X381566D01*
Y-38130D01*
Y-38184D01*
Y-38238D01*
Y-38293D01*
X381512D01*
Y-38347D01*
Y-38401D01*
Y-38455D01*
Y-38509D01*
X381458D01*
Y-38563D01*
Y-38617D01*
Y-38671D01*
X381404D01*
Y-38725D01*
Y-38779D01*
Y-38833D01*
Y-38887D01*
X381350D01*
Y-38941D01*
Y-38995D01*
Y-39050D01*
X381296D01*
Y-39103D01*
Y-39158D01*
Y-39212D01*
X381242D01*
Y-39266D01*
Y-39320D01*
Y-39374D01*
X381188D01*
Y-39428D01*
Y-39482D01*
Y-39536D01*
X381133D01*
Y-39590D01*
Y-39644D01*
Y-39698D01*
X381079D01*
Y-39752D01*
Y-39806D01*
Y-39860D01*
X381025D01*
Y-39915D01*
Y-39968D01*
Y-40023D01*
X380971D01*
Y-40077D01*
Y-40131D01*
X380917D01*
Y-40185D01*
Y-40239D01*
Y-40293D01*
X380863D01*
Y-40347D01*
Y-40401D01*
Y-40455D01*
X380809D01*
Y-40509D01*
Y-40563D01*
X380755D01*
Y-40617D01*
Y-40671D01*
Y-40725D01*
X380701D01*
Y-40780D01*
Y-40834D01*
X380647D01*
Y-40888D01*
Y-40942D01*
X380593D01*
Y-40996D01*
Y-41050D01*
Y-41104D01*
X380539D01*
Y-41158D01*
Y-41212D01*
X380485D01*
Y-41266D01*
Y-41320D01*
X380431D01*
Y-41374D01*
Y-41428D01*
Y-41482D01*
X380377D01*
Y-41536D01*
Y-41590D01*
X380323D01*
Y-41644D01*
Y-41699D01*
X380268D01*
Y-41753D01*
Y-41807D01*
X380214D01*
Y-41861D01*
Y-41915D01*
X380160D01*
Y-41969D01*
Y-42023D01*
X380106D01*
Y-42077D01*
Y-42131D01*
X380052D01*
Y-42185D01*
Y-42239D01*
X379998D01*
Y-42293D01*
Y-42347D01*
X379944D01*
Y-42401D01*
Y-42455D01*
X379890D01*
Y-42509D01*
Y-42564D01*
X379836D01*
Y-42618D01*
Y-42672D01*
X379782D01*
Y-42726D01*
Y-42780D01*
X379728D01*
Y-42834D01*
X379674D01*
Y-42888D01*
Y-42942D01*
X379620D01*
Y-42996D01*
Y-43050D01*
X379566D01*
Y-43104D01*
Y-43158D01*
X379512D01*
Y-43212D01*
X379457D01*
Y-43266D01*
Y-43320D01*
X379403D01*
Y-43374D01*
Y-43429D01*
X379349D01*
Y-43483D01*
Y-43537D01*
X379295D01*
Y-43591D01*
X379241D01*
Y-43645D01*
Y-43699D01*
X379187D01*
Y-43753D01*
X379133D01*
Y-43807D01*
Y-43861D01*
X379079D01*
Y-43915D01*
Y-43969D01*
X379025D01*
Y-44023D01*
X378971D01*
Y-44077D01*
Y-44131D01*
X378917D01*
Y-44185D01*
X378863D01*
Y-44239D01*
Y-44293D01*
X378809D01*
Y-44348D01*
X378755D01*
Y-44402D01*
Y-44456D01*
X378701D01*
Y-44510D01*
X378647D01*
Y-44564D01*
Y-44618D01*
X378592D01*
Y-44672D01*
X378538D01*
Y-44726D01*
Y-44780D01*
X378484D01*
Y-44834D01*
X378430D01*
Y-44888D01*
X378376D01*
Y-44942D01*
Y-44996D01*
X378322D01*
Y-45050D01*
X378268D01*
Y-45104D01*
X378214D01*
Y-45158D01*
Y-45213D01*
X378160D01*
Y-45267D01*
X378106D01*
Y-45321D01*
X378052D01*
Y-45375D01*
Y-45429D01*
X377998D01*
Y-45483D01*
X377944D01*
Y-45537D01*
X377890D01*
Y-45591D01*
Y-45645D01*
X377836D01*
Y-45699D01*
X377782D01*
Y-45753D01*
X377728D01*
Y-45807D01*
X377674D01*
Y-45861D01*
Y-45915D01*
X377619D01*
Y-45969D01*
X377565D01*
Y-46023D01*
X377511D01*
Y-46077D01*
X377457D01*
Y-46132D01*
X377403D01*
Y-46186D01*
Y-46240D01*
X377349D01*
Y-46294D01*
X377295D01*
Y-46348D01*
X377241D01*
Y-46402D01*
X377187D01*
Y-46456D01*
X377133D01*
Y-46510D01*
X377079D01*
Y-46564D01*
X377025D01*
Y-46618D01*
Y-46672D01*
X376971D01*
Y-46726D01*
X376917D01*
Y-46780D01*
X376863D01*
Y-46834D01*
X376809D01*
Y-46889D01*
X376754D01*
Y-46942D01*
X376700D01*
Y-46997D01*
X376646D01*
Y-47051D01*
X376592D01*
Y-47105D01*
X376538D01*
Y-47159D01*
X376484D01*
Y-47213D01*
X376430D01*
Y-47267D01*
X376376D01*
Y-47321D01*
X376322D01*
Y-47375D01*
X376268D01*
Y-47429D01*
X376214D01*
Y-47483D01*
X376160D01*
Y-47537D01*
X376106D01*
Y-47591D01*
X376052D01*
Y-47645D01*
X375997D01*
Y-47699D01*
X375943D01*
Y-47754D01*
X375889D01*
Y-47807D01*
X375835D01*
Y-47862D01*
X375781D01*
Y-47916D01*
X375727D01*
Y-47970D01*
X375673D01*
Y-48024D01*
X375619D01*
Y-48078D01*
X375565D01*
Y-48132D01*
X375457D01*
Y-48186D01*
X375403D01*
Y-48240D01*
X375349D01*
Y-48294D01*
X375295D01*
Y-48348D01*
X375241D01*
Y-48402D01*
X375187D01*
Y-48456D01*
X375132D01*
Y-48510D01*
X375024D01*
Y-48564D01*
X374970D01*
Y-48619D01*
X374916D01*
Y-48673D01*
X374862D01*
Y-48727D01*
X374808D01*
Y-48781D01*
X374700D01*
Y-48835D01*
X374646D01*
Y-48889D01*
X374592D01*
Y-48943D01*
X374538D01*
Y-48997D01*
X374430D01*
Y-49051D01*
X374376D01*
Y-49105D01*
X374322D01*
Y-49159D01*
X374214D01*
Y-49213D01*
X374159D01*
Y-49267D01*
X374105D01*
Y-49321D01*
X373997D01*
Y-49375D01*
X373943D01*
Y-49429D01*
X373889D01*
Y-49483D01*
X373781D01*
Y-49538D01*
X373727D01*
Y-49592D01*
X373673D01*
Y-49646D01*
X373565D01*
Y-49700D01*
X373511D01*
Y-49754D01*
X373403D01*
Y-49808D01*
X373348D01*
Y-49862D01*
X373240D01*
Y-49916D01*
X373186D01*
Y-49970D01*
X373078D01*
Y-50024D01*
X373024D01*
Y-50078D01*
X372916D01*
Y-50132D01*
X372862D01*
Y-50186D01*
X372754D01*
Y-50240D01*
X372646D01*
Y-50294D01*
X372592D01*
Y-50348D01*
X372483D01*
Y-50402D01*
X372429D01*
Y-50457D01*
X372321D01*
Y-50511D01*
X372213D01*
Y-50565D01*
X372159D01*
Y-50619D01*
X372051D01*
Y-50673D01*
X371943D01*
Y-50727D01*
X371835D01*
Y-50781D01*
X371727D01*
Y-50835D01*
X371673D01*
Y-50889D01*
X371565D01*
Y-50943D01*
X371456D01*
Y-50997D01*
X371348D01*
Y-51051D01*
X371240D01*
Y-51105D01*
X371132D01*
Y-51159D01*
X371024D01*
Y-51213D01*
X370916D01*
Y-51267D01*
X370808D01*
Y-51322D01*
X370700D01*
Y-51376D01*
X370591D01*
Y-51430D01*
X370483D01*
Y-51484D01*
X370375D01*
Y-51538D01*
X370213D01*
Y-51592D01*
X370105D01*
Y-51646D01*
X369997D01*
Y-51700D01*
X369888D01*
Y-51754D01*
X369726D01*
Y-51808D01*
X369618D01*
Y-51862D01*
X369456D01*
Y-51916D01*
X369348D01*
Y-51970D01*
X369186D01*
Y-52024D01*
X369078D01*
Y-52078D01*
X368915D01*
Y-52132D01*
X368753D01*
Y-52187D01*
X368591D01*
Y-52241D01*
X368429D01*
Y-52295D01*
X368267D01*
Y-52349D01*
X368105D01*
Y-52403D01*
X367942D01*
Y-52457D01*
X367780D01*
Y-52511D01*
X367564D01*
Y-52565D01*
X367402D01*
Y-52619D01*
X367185D01*
Y-52673D01*
X366969D01*
Y-52727D01*
X366753D01*
Y-52781D01*
X366537D01*
Y-52835D01*
X366320D01*
Y-52889D01*
X366050D01*
Y-52943D01*
X365780D01*
Y-52997D01*
X365456D01*
Y-53052D01*
X365131D01*
Y-53106D01*
X364753D01*
Y-53160D01*
X364320D01*
Y-53214D01*
X363834D01*
Y-53268D01*
X363023D01*
Y-53322D01*
X360914D01*
Y-53268D01*
X360806D01*
Y-53322D01*
X360752D01*
Y-53268D01*
X360157D01*
Y-53214D01*
X359509D01*
Y-53160D01*
X359184D01*
Y-53106D01*
X358806D01*
Y-53052D01*
X358481D01*
Y-52997D01*
X358157D01*
Y-52943D01*
X357887D01*
Y-52889D01*
X357670D01*
Y-52835D01*
X357400D01*
Y-52781D01*
X357184D01*
Y-52727D01*
X356968D01*
Y-52673D01*
X356751D01*
Y-52619D01*
X356535D01*
Y-52565D01*
X356373D01*
Y-52511D01*
X356157D01*
Y-52457D01*
X355995D01*
Y-52403D01*
X355832D01*
Y-52349D01*
X355670D01*
Y-52295D01*
X355508D01*
Y-52241D01*
X355346D01*
Y-52187D01*
X355184D01*
Y-52132D01*
X355022D01*
Y-52078D01*
X354913D01*
Y-52024D01*
X354751D01*
Y-51970D01*
X354589D01*
Y-51916D01*
X354481D01*
Y-51862D01*
X354319D01*
Y-51808D01*
X354211D01*
Y-51754D01*
X354102D01*
Y-51700D01*
X353940D01*
Y-51646D01*
X353832D01*
Y-51592D01*
X353670D01*
Y-51538D01*
X353562D01*
Y-51484D01*
X353454D01*
Y-51430D01*
X353346D01*
Y-51376D01*
X353237D01*
Y-51322D01*
X353129D01*
Y-51267D01*
X353021D01*
Y-51213D01*
X352913D01*
Y-51159D01*
X352805D01*
Y-51105D01*
X352697D01*
Y-51051D01*
X352589D01*
Y-50997D01*
X352481D01*
Y-50943D01*
X352372D01*
Y-50889D01*
X352264D01*
Y-50835D01*
X352210D01*
Y-50781D01*
X352102D01*
Y-50727D01*
X351994D01*
Y-50673D01*
X351886D01*
Y-50619D01*
X351832D01*
Y-50565D01*
X351724D01*
Y-50511D01*
X351616D01*
Y-50457D01*
X351561D01*
Y-50402D01*
X351453D01*
Y-50348D01*
X351345D01*
Y-50294D01*
X351291D01*
Y-50240D01*
X351183D01*
Y-50186D01*
X351075D01*
Y-50132D01*
X351021D01*
Y-50078D01*
X350913D01*
Y-50024D01*
X350859D01*
Y-49970D01*
X350751D01*
Y-49916D01*
X350696D01*
Y-49862D01*
X350588D01*
Y-49808D01*
X350534D01*
Y-49754D01*
X350426D01*
Y-49700D01*
X350372D01*
Y-49646D01*
X350318D01*
Y-49592D01*
X350210D01*
Y-49538D01*
X350156D01*
Y-49483D01*
X350048D01*
Y-49429D01*
X349994D01*
Y-49375D01*
X349940D01*
Y-49321D01*
X349832D01*
Y-49267D01*
X349778D01*
Y-49213D01*
X349723D01*
Y-49159D01*
X349615D01*
Y-49105D01*
X349561D01*
Y-49051D01*
X349507D01*
Y-48997D01*
X349453D01*
Y-48943D01*
X349345D01*
Y-48889D01*
X349291D01*
Y-48835D01*
X349237D01*
Y-48781D01*
X349183D01*
Y-48727D01*
X349075D01*
Y-48673D01*
X349021D01*
Y-48619D01*
X348967D01*
Y-48564D01*
X348913D01*
Y-48510D01*
X348858D01*
Y-48456D01*
X348750D01*
Y-48402D01*
X348696D01*
Y-48348D01*
X348642D01*
Y-48294D01*
X348588D01*
Y-48240D01*
X348534D01*
Y-48186D01*
X348480D01*
Y-48132D01*
X348426D01*
Y-48078D01*
X348318D01*
Y-48024D01*
X348264D01*
Y-47970D01*
X348210D01*
Y-47916D01*
X348156D01*
Y-47862D01*
X348101D01*
Y-47807D01*
X348047D01*
Y-47754D01*
X347993D01*
Y-47699D01*
X347939D01*
Y-47645D01*
X347885D01*
Y-47591D01*
X347831D01*
Y-47537D01*
X347777D01*
Y-47483D01*
X347723D01*
Y-47429D01*
X347669D01*
Y-47375D01*
X347615D01*
Y-47321D01*
X347561D01*
Y-47267D01*
X347507D01*
Y-47213D01*
X347453D01*
Y-47159D01*
X347399D01*
Y-47105D01*
X347345D01*
Y-47051D01*
X347291D01*
Y-46997D01*
X347236D01*
Y-46942D01*
X347182D01*
Y-46889D01*
X347128D01*
Y-46834D01*
X347074D01*
Y-46780D01*
X347020D01*
Y-46726D01*
X346966D01*
Y-46672D01*
Y-46618D01*
X346912D01*
Y-46564D01*
X346858D01*
Y-46510D01*
X345993D01*
Y-46564D01*
X346047D01*
Y-46618D01*
Y-46672D01*
X346101D01*
Y-46726D01*
X346155D01*
Y-46780D01*
X346209D01*
Y-46834D01*
X346263D01*
Y-46889D01*
X346318D01*
Y-46942D01*
X346372D01*
Y-46997D01*
X346426D01*
Y-47051D01*
Y-47105D01*
X346480D01*
Y-47159D01*
X346534D01*
Y-47213D01*
X346588D01*
Y-47267D01*
X346642D01*
Y-47321D01*
X346696D01*
Y-47375D01*
X346750D01*
Y-47429D01*
X346804D01*
Y-47483D01*
X346858D01*
Y-47537D01*
X346912D01*
Y-47591D01*
X346966D01*
Y-47645D01*
X347020D01*
Y-47699D01*
X347074D01*
Y-47754D01*
X347128D01*
Y-47807D01*
X347182D01*
Y-47862D01*
X347236D01*
Y-47916D01*
X347291D01*
Y-47970D01*
X347345D01*
Y-48024D01*
X347399D01*
Y-48078D01*
X347453D01*
Y-48132D01*
X347507D01*
Y-48186D01*
X347561D01*
Y-48240D01*
X347615D01*
Y-48294D01*
X347669D01*
Y-48348D01*
X347723D01*
Y-48402D01*
X347777D01*
Y-48456D01*
X347831D01*
Y-48510D01*
X347885D01*
Y-48564D01*
X347939D01*
Y-48619D01*
X348047D01*
Y-48673D01*
X348101D01*
Y-48727D01*
X348156D01*
Y-48781D01*
X348210D01*
Y-48835D01*
X348264D01*
Y-48889D01*
X348318D01*
Y-48943D01*
X348372D01*
Y-48997D01*
X348480D01*
Y-49051D01*
X348534D01*
Y-49105D01*
X348588D01*
Y-49159D01*
X348642D01*
Y-49213D01*
X348696D01*
Y-49267D01*
X348804D01*
Y-49321D01*
X348858D01*
Y-49375D01*
X348913D01*
Y-49429D01*
X348967D01*
Y-49483D01*
X349075D01*
Y-49538D01*
X349129D01*
Y-49592D01*
X349183D01*
Y-49646D01*
X349237D01*
Y-49700D01*
X349345D01*
Y-49754D01*
X349399D01*
Y-49808D01*
X349453D01*
Y-49862D01*
X349561D01*
Y-49916D01*
X349615D01*
Y-49970D01*
X349669D01*
Y-50024D01*
X349778D01*
Y-50078D01*
X349832D01*
Y-50132D01*
X349940D01*
Y-50186D01*
X349994D01*
Y-50240D01*
X350102D01*
Y-50294D01*
X350156D01*
Y-50348D01*
X350210D01*
Y-50402D01*
X350318D01*
Y-50457D01*
X350372D01*
Y-50511D01*
X350480D01*
Y-50565D01*
X350534D01*
Y-50619D01*
X350642D01*
Y-50673D01*
X350751D01*
Y-50727D01*
X350805D01*
Y-50781D01*
X350913D01*
Y-50835D01*
X350967D01*
Y-50889D01*
X351075D01*
Y-50943D01*
X351183D01*
Y-50997D01*
X351237D01*
Y-51051D01*
X351345D01*
Y-51105D01*
X351453D01*
Y-51159D01*
X351507D01*
Y-51213D01*
X351616D01*
Y-51267D01*
X351724D01*
Y-51322D01*
X351832D01*
Y-51376D01*
X351886D01*
Y-51430D01*
X351994D01*
Y-51484D01*
X352102D01*
Y-51538D01*
X352210D01*
Y-51592D01*
X352318D01*
Y-51646D01*
X352427D01*
Y-51700D01*
X352535D01*
Y-51754D01*
X352643D01*
Y-51808D01*
X352751D01*
Y-51862D01*
X352859D01*
Y-51916D01*
X352967D01*
Y-51970D01*
X353075D01*
Y-52024D01*
X353183D01*
Y-52078D01*
X353292D01*
Y-52132D01*
X353400D01*
Y-52187D01*
X353562D01*
Y-52241D01*
X353670D01*
Y-52295D01*
X353778D01*
Y-52349D01*
X353940D01*
Y-52403D01*
X354048D01*
Y-52457D01*
X354211D01*
Y-52511D01*
X354319D01*
Y-52565D01*
X354481D01*
Y-52619D01*
X354589D01*
Y-52673D01*
X354751D01*
Y-52727D01*
X354913D01*
Y-52781D01*
X355076D01*
Y-52835D01*
X355238D01*
Y-52889D01*
X355400D01*
Y-52943D01*
X355562D01*
Y-52997D01*
X355724D01*
Y-53052D01*
X355887D01*
Y-53106D01*
X356049D01*
Y-53160D01*
X356265D01*
Y-53214D01*
X356427D01*
Y-53268D01*
X356643D01*
Y-53322D01*
X356860D01*
Y-53376D01*
X357076D01*
Y-53430D01*
X357346D01*
Y-53484D01*
X357562D01*
Y-53538D01*
X357779D01*
Y-53592D01*
X358103D01*
Y-53646D01*
X358373D01*
Y-53700D01*
X358698D01*
Y-53754D01*
X359076D01*
Y-53808D01*
X359509D01*
Y-53863D01*
X359995D01*
Y-53917D01*
X360698D01*
Y-53971D01*
X363293D01*
Y-53917D01*
X363942D01*
Y-53863D01*
X364482D01*
Y-53808D01*
X364861D01*
Y-53754D01*
X365239D01*
Y-53700D01*
X365564D01*
Y-53646D01*
X365888D01*
Y-53592D01*
X366158D01*
Y-53538D01*
X366374D01*
Y-53484D01*
X366645D01*
Y-53430D01*
X366861D01*
Y-53376D01*
X367077D01*
Y-53322D01*
X367294D01*
Y-53268D01*
X367510D01*
Y-53214D01*
X367672D01*
Y-53160D01*
X367888D01*
Y-53106D01*
X368050D01*
Y-53052D01*
X368213D01*
Y-52997D01*
X368429D01*
Y-52943D01*
X368591D01*
Y-52889D01*
X368753D01*
Y-52835D01*
X368861D01*
Y-52781D01*
X369023D01*
Y-52727D01*
X369186D01*
Y-52673D01*
X369348D01*
Y-52619D01*
X369456D01*
Y-52565D01*
X369618D01*
Y-52511D01*
X369726D01*
Y-52457D01*
X369888D01*
Y-52403D01*
X369997D01*
Y-52349D01*
X370159D01*
Y-52295D01*
X370267D01*
Y-52241D01*
X370375D01*
Y-52187D01*
X370537D01*
Y-52132D01*
X370645D01*
Y-52078D01*
X370754D01*
Y-52024D01*
X370862D01*
Y-51970D01*
X370970D01*
Y-51916D01*
X371078D01*
Y-51862D01*
X371186D01*
Y-51808D01*
X371294D01*
Y-51754D01*
X371402D01*
Y-51700D01*
X371510D01*
Y-51646D01*
X371619D01*
Y-51592D01*
X371727D01*
Y-51538D01*
X371835D01*
Y-51484D01*
X371943D01*
Y-51430D01*
X372051D01*
Y-51376D01*
X372159D01*
Y-51322D01*
X372213D01*
Y-51267D01*
X372321D01*
Y-51213D01*
X372429D01*
Y-51159D01*
X372538D01*
Y-51105D01*
X372592D01*
Y-51051D01*
X372700D01*
Y-50997D01*
X372808D01*
Y-50943D01*
X372862D01*
Y-50889D01*
X372970D01*
Y-50835D01*
X373024D01*
Y-50781D01*
X373132D01*
Y-50727D01*
X373240D01*
Y-50673D01*
X373294D01*
Y-50619D01*
X373403D01*
Y-50565D01*
X373457D01*
Y-50511D01*
X373565D01*
Y-50457D01*
X373619D01*
Y-50402D01*
X373727D01*
Y-50348D01*
X373781D01*
Y-50294D01*
X373889D01*
Y-50240D01*
X373943D01*
Y-50186D01*
X373997D01*
Y-50132D01*
X374105D01*
Y-50078D01*
X374159D01*
Y-50024D01*
X374268D01*
Y-49970D01*
X374322D01*
Y-49916D01*
X374376D01*
Y-49862D01*
X374484D01*
Y-49808D01*
X374538D01*
Y-49754D01*
X374592D01*
Y-49700D01*
X374700D01*
Y-49646D01*
X374754D01*
Y-49592D01*
X374808D01*
Y-49538D01*
X374916D01*
Y-49483D01*
X374970D01*
Y-49429D01*
X375024D01*
Y-49375D01*
X375079D01*
Y-49321D01*
X375187D01*
Y-49267D01*
X375241D01*
Y-49213D01*
X375295D01*
Y-49159D01*
X375349D01*
Y-49105D01*
X375403D01*
Y-49051D01*
X375511D01*
Y-48997D01*
X375565D01*
Y-48943D01*
X375619D01*
Y-48889D01*
X375673D01*
Y-48835D01*
X375727D01*
Y-48781D01*
X375781D01*
Y-48727D01*
X375835D01*
Y-48673D01*
X375943D01*
Y-48619D01*
X375997D01*
Y-48564D01*
X376052D01*
Y-48510D01*
X376106D01*
Y-48456D01*
X376160D01*
Y-48402D01*
X376214D01*
Y-48348D01*
X376268D01*
Y-48294D01*
X376322D01*
Y-48240D01*
X376376D01*
Y-48186D01*
X376430D01*
Y-48132D01*
X376484D01*
Y-48078D01*
X376538D01*
Y-48024D01*
X376592D01*
Y-47970D01*
X376646D01*
Y-47916D01*
X376700D01*
Y-47862D01*
X376754D01*
Y-47807D01*
X376809D01*
Y-47754D01*
X376863D01*
Y-47699D01*
X376917D01*
Y-47645D01*
X376971D01*
Y-47591D01*
X377025D01*
Y-47537D01*
X377079D01*
Y-47483D01*
X377133D01*
Y-47429D01*
X377187D01*
Y-47375D01*
X377241D01*
Y-47321D01*
X377295D01*
Y-47267D01*
X377349D01*
Y-47213D01*
X377403D01*
Y-47159D01*
X377457D01*
Y-47105D01*
X377511D01*
Y-47051D01*
X377565D01*
Y-46997D01*
Y-46942D01*
X377619D01*
Y-46889D01*
X377674D01*
Y-46834D01*
X377728D01*
Y-46780D01*
X377782D01*
Y-46726D01*
X377836D01*
Y-46672D01*
X377890D01*
Y-46618D01*
X377944D01*
Y-46564D01*
Y-46510D01*
X377998D01*
Y-46456D01*
X378052D01*
Y-46402D01*
X378106D01*
Y-46348D01*
X378160D01*
Y-46294D01*
Y-46240D01*
X378214D01*
Y-46186D01*
X378268D01*
Y-46132D01*
X378322D01*
Y-46077D01*
X378376D01*
Y-46023D01*
Y-45969D01*
X378430D01*
Y-45915D01*
X378484D01*
Y-45861D01*
X378538D01*
Y-45807D01*
X378592D01*
Y-45753D01*
Y-45699D01*
X378647D01*
Y-45645D01*
X378701D01*
Y-45591D01*
X378755D01*
Y-45537D01*
Y-45483D01*
X378809D01*
Y-45429D01*
X378863D01*
Y-45375D01*
X378917D01*
Y-45321D01*
Y-45267D01*
X378971D01*
Y-45213D01*
X379025D01*
Y-45158D01*
Y-45104D01*
X379079D01*
Y-45050D01*
X379133D01*
Y-44996D01*
X379187D01*
Y-44942D01*
Y-44888D01*
X379241D01*
Y-44834D01*
X379295D01*
Y-44780D01*
Y-44726D01*
X379349D01*
Y-44672D01*
X379403D01*
Y-44618D01*
Y-44564D01*
X379457D01*
Y-44510D01*
X379512D01*
Y-44456D01*
Y-44402D01*
X379566D01*
Y-44348D01*
X379620D01*
Y-44293D01*
Y-44239D01*
X379674D01*
Y-44185D01*
Y-44131D01*
X379728D01*
Y-44077D01*
X379782D01*
Y-44023D01*
Y-43969D01*
X379836D01*
Y-43915D01*
X379890D01*
Y-43861D01*
Y-43807D01*
X379944D01*
Y-43753D01*
Y-43699D01*
X379998D01*
Y-43645D01*
Y-43591D01*
X380052D01*
Y-43537D01*
X380106D01*
Y-43483D01*
Y-43429D01*
X380160D01*
Y-43374D01*
Y-43320D01*
X380214D01*
Y-43266D01*
Y-43212D01*
X380268D01*
Y-43158D01*
Y-43104D01*
X380323D01*
Y-43050D01*
X380377D01*
Y-42996D01*
Y-42942D01*
X380431D01*
Y-42888D01*
Y-42834D01*
X380485D01*
Y-42780D01*
Y-42726D01*
X380539D01*
Y-42672D01*
Y-42618D01*
X380593D01*
Y-42564D01*
Y-42509D01*
X380647D01*
Y-42455D01*
Y-42401D01*
X380701D01*
Y-42347D01*
Y-42293D01*
X380755D01*
Y-42239D01*
Y-42185D01*
X380809D01*
Y-42131D01*
Y-42077D01*
X380863D01*
Y-42023D01*
Y-41969D01*
X380917D01*
Y-41915D01*
Y-41861D01*
X380971D01*
Y-41807D01*
Y-41753D01*
X381025D01*
Y-41699D01*
Y-41644D01*
X381079D01*
Y-41590D01*
Y-41536D01*
Y-41482D01*
X381133D01*
Y-41428D01*
Y-41374D01*
X381188D01*
Y-41320D01*
Y-41266D01*
X381242D01*
Y-41212D01*
Y-41158D01*
Y-41104D01*
X381296D01*
Y-41050D01*
Y-40996D01*
X381350D01*
Y-40942D01*
Y-40888D01*
Y-40834D01*
X381404D01*
Y-40780D01*
Y-40725D01*
X381458D01*
Y-40671D01*
Y-40617D01*
Y-40563D01*
X381512D01*
Y-40509D01*
Y-40455D01*
X381566D01*
Y-40401D01*
Y-40347D01*
Y-40293D01*
X381620D01*
Y-40239D01*
Y-40185D01*
Y-40131D01*
X381674D01*
Y-40077D01*
Y-40023D01*
Y-39968D01*
X381728D01*
Y-39915D01*
Y-39860D01*
Y-39806D01*
X381782D01*
Y-39752D01*
Y-39698D01*
Y-39644D01*
X381836D01*
Y-39590D01*
Y-39536D01*
Y-39482D01*
X381890D01*
Y-39428D01*
Y-39374D01*
Y-39320D01*
X381944D01*
Y-39266D01*
Y-39212D01*
Y-39158D01*
X381998D01*
Y-39103D01*
Y-39050D01*
Y-38995D01*
X382052D01*
Y-38941D01*
Y-38887D01*
Y-38833D01*
Y-38779D01*
X382107D01*
Y-38725D01*
Y-38671D01*
Y-38617D01*
X382161D01*
Y-38563D01*
Y-38509D01*
Y-38455D01*
Y-38401D01*
X382215D01*
Y-38347D01*
Y-38293D01*
Y-38238D01*
Y-38184D01*
X382269D01*
Y-38130D01*
Y-38076D01*
Y-38022D01*
Y-37968D01*
X382323D01*
Y-37914D01*
Y-37860D01*
Y-37806D01*
Y-37752D01*
X382377D01*
Y-37698D01*
Y-37644D01*
Y-37590D01*
Y-37536D01*
Y-37482D01*
X382431D01*
Y-37428D01*
Y-37374D01*
Y-37319D01*
Y-37265D01*
Y-37211D01*
X382485D01*
Y-37157D01*
Y-37103D01*
Y-37049D01*
Y-36995D01*
Y-36941D01*
X382539D01*
Y-36887D01*
Y-36833D01*
Y-36779D01*
Y-36725D01*
Y-36671D01*
X382593D01*
Y-36617D01*
Y-36563D01*
Y-36509D01*
Y-36454D01*
Y-36400D01*
Y-36346D01*
X382647D01*
Y-36292D01*
Y-36238D01*
Y-36184D01*
Y-36130D01*
Y-36076D01*
Y-36022D01*
Y-35968D01*
X382701D01*
Y-35914D01*
Y-35860D01*
Y-35806D01*
Y-35752D01*
Y-35698D01*
Y-35644D01*
Y-35590D01*
Y-35535D01*
X382755D01*
Y-35481D01*
Y-35427D01*
Y-35373D01*
Y-35319D01*
Y-35265D01*
Y-35211D01*
Y-35157D01*
Y-35103D01*
Y-35049D01*
Y-34995D01*
X382809D01*
Y-34941D01*
X382755D01*
Y-34887D01*
X382809D01*
Y-34833D01*
Y-34779D01*
Y-34725D01*
Y-34670D01*
Y-34616D01*
Y-34562D01*
Y-34508D01*
Y-34454D01*
Y-34400D01*
Y-34346D01*
Y-34292D01*
X382863D01*
Y-34238D01*
Y-34184D01*
Y-34130D01*
Y-34076D01*
Y-34022D01*
Y-33968D01*
Y-33914D01*
Y-33860D01*
Y-33806D01*
Y-33751D01*
Y-33697D01*
D02*
G37*
%LPD*%
G36*
X353021Y-36454D02*
Y-36509D01*
Y-36563D01*
Y-36617D01*
Y-36671D01*
Y-36725D01*
Y-36779D01*
Y-36833D01*
Y-36887D01*
Y-36941D01*
Y-36995D01*
Y-37049D01*
Y-37103D01*
Y-37157D01*
Y-37211D01*
Y-37265D01*
Y-37319D01*
Y-37374D01*
Y-37428D01*
Y-37482D01*
Y-37536D01*
Y-37590D01*
Y-37644D01*
Y-37698D01*
Y-37752D01*
Y-37806D01*
Y-37860D01*
Y-37914D01*
Y-37968D01*
Y-38022D01*
Y-38076D01*
Y-38130D01*
Y-38184D01*
Y-38238D01*
Y-38293D01*
Y-38347D01*
Y-38401D01*
Y-38455D01*
Y-38509D01*
Y-38563D01*
Y-38617D01*
Y-38671D01*
Y-38725D01*
Y-38779D01*
Y-38833D01*
Y-38887D01*
Y-38941D01*
Y-38995D01*
Y-39050D01*
Y-39103D01*
Y-39158D01*
Y-39212D01*
Y-39266D01*
X348967D01*
Y-39212D01*
Y-39158D01*
Y-39103D01*
Y-39050D01*
Y-38995D01*
Y-38941D01*
Y-38887D01*
Y-38833D01*
Y-38779D01*
Y-38725D01*
Y-38671D01*
Y-38617D01*
Y-38563D01*
Y-38509D01*
Y-38455D01*
Y-38401D01*
Y-38347D01*
Y-38293D01*
Y-38238D01*
Y-38184D01*
Y-38130D01*
Y-38076D01*
Y-38022D01*
Y-37968D01*
Y-37914D01*
Y-37860D01*
Y-37806D01*
Y-37752D01*
Y-37698D01*
Y-37644D01*
Y-37590D01*
Y-37536D01*
Y-37482D01*
Y-37428D01*
Y-37374D01*
Y-37319D01*
Y-37265D01*
Y-37211D01*
Y-37157D01*
Y-37103D01*
Y-37049D01*
Y-36995D01*
Y-36941D01*
Y-36887D01*
Y-36833D01*
Y-36779D01*
Y-36725D01*
Y-36671D01*
Y-36617D01*
Y-36563D01*
Y-36509D01*
Y-36454D01*
Y-36400D01*
X353021D01*
Y-36454D01*
D02*
G37*
G36*
X341344Y-36563D02*
X341398D01*
Y-36617D01*
Y-36671D01*
Y-36725D01*
Y-36779D01*
Y-36833D01*
Y-36887D01*
Y-36941D01*
Y-36995D01*
Y-37049D01*
Y-37103D01*
Y-37157D01*
Y-37211D01*
Y-37265D01*
Y-37319D01*
Y-37374D01*
Y-37428D01*
Y-37482D01*
Y-37536D01*
Y-37590D01*
Y-37644D01*
Y-37698D01*
Y-37752D01*
Y-37806D01*
Y-37860D01*
Y-37914D01*
Y-37968D01*
Y-38022D01*
Y-38076D01*
Y-38130D01*
Y-38184D01*
Y-38238D01*
Y-38293D01*
Y-38347D01*
Y-38401D01*
Y-38455D01*
Y-38509D01*
Y-38563D01*
Y-38617D01*
Y-38671D01*
Y-38725D01*
Y-38779D01*
Y-38833D01*
Y-38887D01*
Y-38941D01*
Y-38995D01*
Y-39050D01*
Y-39103D01*
Y-39158D01*
Y-39212D01*
Y-39266D01*
Y-39320D01*
Y-39374D01*
Y-39428D01*
Y-39482D01*
Y-39536D01*
Y-39590D01*
Y-39644D01*
Y-39698D01*
Y-39752D01*
Y-39806D01*
Y-39860D01*
Y-39915D01*
Y-39968D01*
Y-40023D01*
Y-40077D01*
Y-40131D01*
Y-40185D01*
Y-40239D01*
Y-40293D01*
Y-40347D01*
Y-40401D01*
Y-40455D01*
Y-40509D01*
Y-40563D01*
Y-40617D01*
Y-40671D01*
Y-40725D01*
Y-40780D01*
Y-40834D01*
Y-40888D01*
Y-40942D01*
Y-40996D01*
Y-41050D01*
Y-41104D01*
Y-41158D01*
Y-41212D01*
Y-41266D01*
Y-41320D01*
Y-41374D01*
Y-41428D01*
Y-41482D01*
Y-41536D01*
Y-41590D01*
Y-41644D01*
Y-41699D01*
Y-41753D01*
Y-41807D01*
Y-41861D01*
Y-41915D01*
Y-41969D01*
Y-42023D01*
Y-42077D01*
Y-42131D01*
Y-42185D01*
Y-42239D01*
Y-42293D01*
Y-42347D01*
Y-42401D01*
Y-42455D01*
Y-42509D01*
Y-42564D01*
X337451D01*
Y-42509D01*
Y-42455D01*
Y-42401D01*
Y-42347D01*
Y-42293D01*
Y-42239D01*
Y-42185D01*
Y-42131D01*
Y-42077D01*
Y-42023D01*
Y-41969D01*
Y-41915D01*
Y-41861D01*
Y-41807D01*
Y-41753D01*
Y-41699D01*
Y-41644D01*
Y-41590D01*
Y-41536D01*
Y-41482D01*
Y-41428D01*
Y-41374D01*
Y-41320D01*
Y-41266D01*
Y-41212D01*
Y-41158D01*
Y-41104D01*
Y-41050D01*
Y-40996D01*
Y-40942D01*
Y-40888D01*
Y-40834D01*
Y-40780D01*
Y-40725D01*
Y-40671D01*
Y-40617D01*
Y-40563D01*
Y-40509D01*
Y-40455D01*
Y-40401D01*
Y-40347D01*
Y-40293D01*
Y-40239D01*
Y-40185D01*
Y-40131D01*
Y-40077D01*
Y-40023D01*
Y-39968D01*
Y-39915D01*
Y-39860D01*
Y-39806D01*
Y-39752D01*
Y-39698D01*
Y-39644D01*
Y-39590D01*
Y-39536D01*
Y-39482D01*
Y-39428D01*
Y-39374D01*
Y-39320D01*
Y-39266D01*
Y-39212D01*
Y-39158D01*
Y-39103D01*
Y-39050D01*
Y-38995D01*
Y-38941D01*
Y-38887D01*
Y-38833D01*
Y-38779D01*
Y-38725D01*
Y-38671D01*
Y-38617D01*
Y-38563D01*
Y-38509D01*
Y-38455D01*
Y-38401D01*
Y-38347D01*
Y-38293D01*
Y-38238D01*
Y-38184D01*
Y-38130D01*
Y-38076D01*
Y-38022D01*
Y-37968D01*
Y-37914D01*
Y-37860D01*
Y-37806D01*
Y-37752D01*
Y-37698D01*
Y-37644D01*
Y-37590D01*
Y-37536D01*
Y-37482D01*
Y-37428D01*
Y-37374D01*
Y-37319D01*
Y-37265D01*
Y-37211D01*
Y-37157D01*
Y-37103D01*
Y-37049D01*
Y-36995D01*
Y-36941D01*
Y-36887D01*
Y-36833D01*
Y-36779D01*
Y-36725D01*
Y-36671D01*
Y-36617D01*
Y-36563D01*
X337560D01*
Y-36509D01*
X337614D01*
Y-36563D01*
X337722D01*
Y-36509D01*
X337776D01*
Y-36563D01*
X341290D01*
Y-36509D01*
X341344D01*
Y-36563D01*
D02*
G37*
%LPC*%
G36*
X647169Y-155896D02*
Y-159917D01*
X651191D01*
X651001Y-159209D01*
X650247Y-157904D01*
X649182Y-156839D01*
X647878Y-156086D01*
X647169Y-155896D01*
D02*
G37*
G36*
X644169Y-155896D02*
X643461Y-156086D01*
X642156Y-156839D01*
X641091Y-157904D01*
X640338Y-159209D01*
X640148Y-159917D01*
X644169D01*
Y-155896D01*
D02*
G37*
G36*
Y-162917D02*
X640148D01*
X640338Y-163626D01*
X641091Y-164930D01*
X642156Y-165996D01*
X643461Y-166749D01*
X644169Y-166938D01*
Y-162917D01*
D02*
G37*
G36*
X651190D02*
X647169D01*
Y-166938D01*
X647878Y-166749D01*
X649182Y-165996D01*
X650247Y-164930D01*
X651001Y-163626D01*
X651190Y-162917D01*
D02*
G37*
G36*
X647169Y-172432D02*
Y-176453D01*
X651191D01*
X651001Y-175744D01*
X650247Y-174440D01*
X649182Y-173375D01*
X647878Y-172621D01*
X647169Y-172432D01*
D02*
G37*
G36*
X644169Y-172432D02*
X643461Y-172621D01*
X642156Y-173375D01*
X641091Y-174440D01*
X640338Y-175744D01*
X640148Y-176453D01*
X644169D01*
Y-172432D01*
D02*
G37*
G36*
Y-179453D02*
X640148D01*
X640338Y-180161D01*
X641091Y-181466D01*
X642156Y-182531D01*
X643461Y-183284D01*
X644169Y-183474D01*
Y-179453D01*
D02*
G37*
G36*
X651190D02*
X647169D01*
Y-183474D01*
X647878Y-183284D01*
X649182Y-182531D01*
X650247Y-181466D01*
X651001Y-180161D01*
X651190Y-179453D01*
D02*
G37*
G36*
X647169Y-188967D02*
Y-192988D01*
X651190D01*
X651001Y-192280D01*
X650247Y-190975D01*
X649182Y-189910D01*
X647878Y-189157D01*
X647169Y-188967D01*
D02*
G37*
G36*
X644169Y-188967D02*
X643461Y-189157D01*
X642156Y-189910D01*
X641091Y-190975D01*
X640338Y-192280D01*
X640148Y-192988D01*
X644169D01*
Y-188967D01*
D02*
G37*
G36*
Y-195988D02*
X640148D01*
X640338Y-196696D01*
X641091Y-198001D01*
X642156Y-199066D01*
X643461Y-199820D01*
X644169Y-200009D01*
Y-195988D01*
D02*
G37*
G36*
X651191D02*
X647169D01*
Y-200009D01*
X647878Y-199820D01*
X649182Y-199066D01*
X650247Y-198001D01*
X651001Y-196696D01*
X651191Y-195988D01*
D02*
G37*
G36*
X611895Y-220828D02*
X610940D01*
X610058Y-221194D01*
X609383Y-221869D01*
X609017Y-222751D01*
Y-223706D01*
X609383Y-224588D01*
X610058Y-225263D01*
X610245Y-225341D01*
Y-225841D01*
X610058Y-225918D01*
X609383Y-226593D01*
X609017Y-227475D01*
Y-228430D01*
X609383Y-229312D01*
X610058Y-229987D01*
X610940Y-230353D01*
X611895D01*
X612777Y-229987D01*
X613452Y-229312D01*
X613817Y-228430D01*
Y-227475D01*
X613452Y-226593D01*
X612777Y-225918D01*
X612590Y-225841D01*
Y-225341D01*
X612777Y-225263D01*
X613452Y-224588D01*
X613817Y-223706D01*
Y-222751D01*
X613452Y-221869D01*
X612777Y-221194D01*
X611895Y-220828D01*
D02*
G37*
%LPD*%
D10*
X240945Y-309638D02*
Y-133465D01*
Y-309638D02*
X258472Y-327165D01*
D18*
X369921Y-212598D02*
G03*
X379921Y-202598I0J10000D01*
G01*
X322441Y-212598D02*
G03*
X314503Y-220537I0J-7938D01*
G01*
X371031Y-210630D02*
G03*
X377921Y-203740I0J6890D01*
G01*
X321811Y-210630D02*
G03*
X311811Y-220630I0J-10000D01*
G01*
Y-224944D02*
G03*
X314864Y-227997I3053J0D01*
G01*
X565202Y-232829D02*
Y-144095D01*
Y-123622D02*
Y-25789D01*
Y-144095D02*
X570079Y-139218D01*
Y-128498D01*
X565202Y-123622D02*
X570079Y-128498D01*
X542491Y-237947D02*
X552362Y-228076D01*
Y-12992D01*
X544291Y-4921D02*
X552362Y-12992D01*
X336261Y-249647D02*
X545628D01*
X563902Y-231373D02*
Y-21216D01*
X545628Y-249647D02*
X563902Y-231373D01*
X328740Y-250984D02*
X547047D01*
X565202Y-232829D01*
X371228Y-200000D02*
X372016Y-200787D01*
X322047Y-200000D02*
X371228D01*
X307480Y-214567D02*
X322047Y-200000D01*
X307480Y-228346D02*
Y-214567D01*
Y-228346D02*
X309768Y-230634D01*
X315226D01*
X322441Y-212598D02*
X369921D01*
X314503Y-225180D02*
Y-220537D01*
X379921Y-202598D02*
Y-201740D01*
X321811Y-210630D02*
X371031D01*
X311811Y-224944D02*
Y-220630D01*
X237402Y-318094D02*
X246472Y-327165D01*
X237402Y-318094D02*
Y-133465D01*
X329819Y-243205D02*
X336261Y-249647D01*
X325787Y-243205D02*
X329819D01*
X321850Y-244094D02*
X328740Y-250984D01*
X563902Y-21216D02*
X589055Y3937D01*
X565202Y-25789D02*
X593208Y2217D01*
Y9784D01*
X589055Y13937D02*
X593208Y9784D01*
X321850Y-244094D02*
Y-235236D01*
X323724Y-233362D01*
X325787D01*
X99410Y-65797D02*
X181232D01*
X298242Y-182806D01*
X373057D01*
X80596Y-142270D02*
X95250D01*
X97409Y-140111D01*
X105409Y-143458D02*
Y-140111D01*
X101409Y-142561D02*
Y-140111D01*
X109409Y-143135D02*
Y-140111D01*
X157350Y-38238D02*
X299319Y-180206D01*
X65945Y-44143D02*
X71850Y-38238D01*
X157350D01*
X323882Y-241205D02*
X329657D01*
X329496Y-239205D02*
X337338Y-247047D01*
X329657Y-241205D02*
X336800Y-248347D01*
X337338Y-247047D02*
X540744D01*
X336800Y-248347D02*
X541283D01*
X323850Y-237205D02*
X329334D01*
X325787Y-239205D02*
X329496D01*
X329334Y-237205D02*
X337877Y-245747D01*
X540206D01*
X420541Y-226591D02*
X543276D01*
X374157Y-180206D02*
X420541Y-226591D01*
X323819Y-227362D02*
X414444D01*
X425029Y-237947D01*
X544294Y-224265D02*
X545276Y-225246D01*
X544089Y-229106D02*
X545276Y-227920D01*
Y-225246D01*
X549213Y-228346D02*
Y-211466D01*
X544291Y-233268D02*
X549213Y-228346D01*
X420657Y-230406D02*
X545184D01*
X547913Y-227678D02*
Y-219024D01*
X545184Y-230406D02*
X547913Y-227678D01*
X544294Y-224265D02*
Y-224248D01*
X421218Y-229106D02*
X544089D01*
X543029Y-239247D02*
X557402Y-224874D01*
X560002Y-225951D02*
Y-14857D01*
X562602Y-227028D02*
Y-17976D01*
X540206Y-245747D02*
X560002Y-225951D01*
X557402Y-224874D02*
Y-16064D01*
X543568Y-240547D02*
X558702Y-225412D01*
X540744Y-247047D02*
X561302Y-226489D01*
X423952Y-240547D02*
X543568D01*
X558702Y-225412D02*
Y-15395D01*
X424491Y-239247D02*
X543029D01*
X541283Y-248347D02*
X562602Y-227028D01*
X561302Y-226489D02*
Y-17438D01*
X425029Y-237947D02*
X542491D01*
X475361Y-137615D02*
X549213Y-211466D01*
X544291Y-215403D02*
X547913Y-219024D01*
X325787Y-229362D02*
X414606D01*
X424491Y-239247D01*
X323882Y-231362D02*
X414767D01*
X423952Y-240547D01*
X-23622Y-184055D02*
X39110D01*
X70495Y-152670D01*
X544291Y5906D02*
X547244Y8858D01*
X553976D02*
X559055Y13937D01*
X547244Y8858D02*
X553976D01*
X544291Y-4921D02*
Y5906D01*
X554528Y-11220D02*
X558702Y-15395D01*
X559055Y-13909D02*
X560002Y-14857D01*
X562602Y-17976D02*
X579055Y-1524D01*
X553208Y-11869D02*
X557402Y-16064D01*
X561302Y-17438D02*
X569055Y-9685D01*
X559055Y-13909D02*
Y5979D01*
X569055Y-9685D02*
Y3937D01*
X579055Y-1524D02*
Y3937D01*
X554528Y-11220D02*
Y5660D01*
X553208Y-11869D02*
Y6179D01*
X556419Y9390D01*
X323850Y-241173D02*
X323882Y-241205D01*
X175197Y-57923D02*
X298780Y-181506D01*
X299319Y-180206D02*
X374157D01*
X298780Y-181506D02*
X373618D01*
X323819Y-231299D02*
X323882Y-231362D01*
X373618Y-181506D02*
X421218Y-229106D01*
X373057Y-182806D02*
X420657Y-230406D01*
X554528Y5660D02*
X556957Y8090D01*
X569055Y12555D02*
Y13937D01*
X566947Y10447D02*
X569055Y12555D01*
X566947Y10392D02*
Y10447D01*
X565945Y9390D02*
X566947Y10392D01*
X556419Y9390D02*
X565945D01*
X556957Y8090D02*
X576556D01*
X578250Y9784D01*
Y13132D02*
X579055Y13937D01*
X578250Y9784D02*
Y13132D01*
X13780Y-335630D02*
X29880Y-319529D01*
X-23622Y-342520D02*
X10567D01*
X32480Y-320606D01*
X31180Y-320068D02*
Y-206693D01*
X-23622Y-335630D02*
X13780D01*
X29880Y-319529D02*
Y-206154D01*
X-23622Y-339567D02*
X11681D01*
X31180Y-320068D01*
X32480Y-320606D02*
Y-207231D01*
X10827Y-237205D02*
X24680Y-223351D01*
X-23622Y-237205D02*
X10827D01*
X22080Y-222274D02*
Y-202923D01*
X-23622Y-229331D02*
X15024D01*
X24680Y-223351D02*
Y-204000D01*
X-23622Y-233268D02*
X12925D01*
X23380Y-222813D02*
Y-203462D01*
X12925Y-233268D02*
X23380Y-222813D01*
X15024Y-229331D02*
X22080Y-222274D01*
X27280Y-273771D02*
Y-205077D01*
X25980Y-273232D02*
Y-204539D01*
X28580Y-205616D02*
X73726Y-160470D01*
X16732Y-282480D02*
X25980Y-273232D01*
Y-204539D02*
X72649Y-157870D01*
X14634Y-286417D02*
X27280Y-273771D01*
X23380Y-203462D02*
X71572Y-155270D01*
X12535Y-290354D02*
X28580Y-274309D01*
X32480Y-207231D02*
X75341Y-164370D01*
X31180Y-206693D02*
X74803Y-163070D01*
X28580Y-274309D02*
Y-205616D01*
X24680Y-204000D02*
X72110Y-156570D01*
X27280Y-205077D02*
X73187Y-159170D01*
X29880Y-206154D02*
X74264Y-161770D01*
X22080Y-202923D02*
X71034Y-153970D01*
X-23622Y-282480D02*
X16732D01*
X-23622Y-290354D02*
X12535D01*
X-23622Y-286417D02*
X14634D01*
X72649Y-157870D02*
X107544D01*
X72110Y-156570D02*
X107005D01*
X71572Y-155270D02*
X106467D01*
X-23622Y-181102D02*
X40224D01*
X74803Y-163070D02*
X109698D01*
X73726Y-160470D02*
X108621D01*
X74264Y-161770D02*
X109159D01*
X73187Y-159170D02*
X108082D01*
X69957Y-151370D02*
X104851D01*
X69418Y-150070D02*
X104313D01*
X75341Y-164370D02*
X110236D01*
X71034Y-153970D02*
X105929D01*
X40224Y-181102D02*
X69957Y-151370D01*
X42323Y-177165D02*
X69418Y-150070D01*
X-23622Y-177165D02*
X42323D01*
X70495Y-152670D02*
X105390D01*
X-23622Y-102362D02*
X35173D01*
X-23622Y-62992D02*
X-520D01*
X-23622Y-60039D02*
X-1634D01*
X80058Y-143570D02*
X97572D01*
X-520Y-62992D02*
X80058Y-143570D01*
X39370Y-110236D02*
X77904Y-148770D01*
X35173Y-102362D02*
X78981Y-146170D01*
X37272Y-106299D02*
X78442Y-147470D01*
X78981Y-146170D02*
X102698D01*
X-23622Y-66929D02*
X1578D01*
X78442Y-147470D02*
X103236D01*
X-23622Y-110236D02*
X39370D01*
X79519Y-144870D02*
X99100D01*
X77904Y-148770D02*
X103775D01*
X-1634Y-60039D02*
X80596Y-142270D01*
X-23622Y-106299D02*
X37272D01*
X1578Y-66929D02*
X79519Y-144870D01*
X102698Y-146170D02*
X105409Y-143458D01*
X103236Y-147470D02*
X107256Y-143450D01*
Y-141885D01*
X107409Y-141732D01*
X131258Y-139671D02*
Y-123124D01*
X123458Y-136440D02*
Y-126411D01*
X127358Y-138056D02*
Y-124740D01*
X132558Y-140210D02*
Y-122586D01*
X124758Y-136979D02*
Y-125817D01*
X117126Y-137257D02*
Y-132047D01*
X104851Y-151370D02*
X120858Y-135363D01*
X109698Y-163070D02*
X132558Y-140210D01*
X104313Y-150070D02*
X117126Y-137257D01*
X105390Y-152670D02*
X122158Y-135902D01*
X109159Y-161770D02*
X131258Y-139671D01*
X108082Y-159170D02*
X128658Y-138594D01*
X122158Y-135902D02*
Y-130032D01*
X120858Y-135363D02*
Y-131810D01*
X107005Y-156570D02*
X126058Y-137517D01*
Y-125278D01*
X108621Y-160470D02*
X129958Y-139133D01*
X133858Y-140748D02*
Y-122047D01*
X129958Y-139133D02*
Y-123663D01*
X105929Y-153970D02*
X123458Y-136440D01*
X106467Y-155270D02*
X124758Y-136979D01*
X103775Y-148770D02*
X109409Y-143135D01*
X107544Y-157870D02*
X127358Y-138056D01*
X110236Y-164370D02*
X133858Y-140748D01*
X128658Y-138594D02*
Y-124201D01*
X99100Y-144870D02*
X101409Y-142561D01*
X97572Y-143570D02*
X99410Y-141732D01*
X121095Y-122153D02*
X124758Y-125817D01*
X119095Y-130047D02*
X120858Y-131810D01*
X120702Y-119921D02*
X126058Y-125278D01*
X120173Y-128047D02*
X122158Y-130032D01*
X114693Y-110236D02*
X128658Y-124201D01*
X114823Y-112205D02*
X127358Y-124740D01*
X113579Y-107283D02*
X129958Y-123663D01*
X114081Y-105947D02*
X131258Y-123124D01*
X114619Y-104647D02*
X132558Y-122586D01*
X115157Y-103347D02*
X133858Y-122047D01*
X121094Y-124047D02*
X123458Y-126411D01*
X117126Y-128047D02*
X120173D01*
X117126Y-124047D02*
X121094D01*
X107346Y-110236D02*
X114693D01*
X104553Y-105947D02*
X114081D01*
X119201Y-122153D02*
X121095D01*
X109441Y-112205D02*
X114823D01*
X119095Y-122047D02*
X119201Y-122153D01*
X103347Y-103347D02*
X115157D01*
X107283Y-107283D02*
X113579D01*
X117126Y-119921D02*
X120702D01*
X104015Y-104647D02*
X114619D01*
X97284Y-109409D02*
X103347Y-103347D01*
X97284Y-112205D02*
Y-109409D01*
X99499Y-110083D02*
Y-109162D01*
X101347Y-112142D02*
Y-109153D01*
X99347Y-110236D02*
X99499Y-110083D01*
Y-109162D02*
X104015Y-104647D01*
X101347Y-109153D02*
X104553Y-105947D01*
X105347Y-109221D02*
X107283Y-107283D01*
X105347Y-112205D02*
Y-109221D01*
X101284Y-112205D02*
X101347Y-112142D01*
X109409Y-112236D02*
X109441Y-112205D01*
X469521Y-137615D02*
X475361D01*
X512795Y-128789D02*
X524508D01*
X512795Y-125836D02*
X524606D01*
X524508Y-128789D02*
X524557Y-128740D01*
X190354Y-401230D02*
Y-377411D01*
Y-401230D02*
X190551Y-401427D01*
X99410Y-57923D02*
X175197D01*
X158736Y-377411D02*
X178543D01*
X151260Y-402150D02*
X151753Y-401657D01*
Y-384394D02*
X158736Y-377411D01*
X151753Y-401657D02*
Y-384394D01*
X483268Y-114025D02*
X486536Y-110757D01*
X489205Y-112057D02*
X496063D01*
X512795Y-128789D01*
X497716Y-110757D02*
X512795Y-125836D01*
X486536Y-110757D02*
X497716D01*
X487205Y-114057D02*
X489205Y-112057D01*
X464328Y-146397D02*
X464448Y-146516D01*
X65945Y-50049D02*
Y-44143D01*
X241811Y-404100D02*
X241941Y-403970D01*
X206378Y-404100D02*
X206441Y-404037D01*
X273307Y-404100D02*
X273441Y-403966D01*
D21*
X218439Y-374114D02*
G03*
X218310Y-374444I371J-335D01*
G01*
X206441Y-378907D02*
G03*
X206496Y-378774I-133J133D01*
G01*
X269496Y-374321D02*
G03*
X269488Y-374409I492J-88D01*
G01*
X269441Y-378907D02*
G03*
X269488Y-378793I-114J114D01*
G01*
X237941Y-378907D02*
G03*
X237992Y-378783I-124J124D01*
G01*
X253346Y-378679D02*
G03*
X253441Y-378907I323J0D01*
G01*
X256890Y-378783D02*
G03*
X256941Y-378907I175J0D01*
G01*
X253655Y-374421D02*
G03*
X253346Y-374879I191J-462D01*
G01*
X241811Y-404100D02*
G03*
X241941Y-403786I-314J314D01*
G01*
X273441Y-382293D02*
G03*
X273307Y-382616I323J-323D01*
G01*
X269441Y-382293D02*
G03*
X269370Y-382464I171J-171D01*
G01*
X256941Y-400125D02*
G03*
X257480Y-401427I1841J0D01*
G01*
X253622Y-382730D02*
G03*
X253441Y-382293I-618J0D01*
G01*
Y-401180D02*
G03*
X253543Y-401427I349J0D01*
G01*
X206441Y-382293D02*
G03*
X206378Y-382445I152J-152D01*
G01*
X206299Y-401427D02*
G03*
X206441Y-401085I-342J342D01*
G01*
X210236Y-401427D02*
G03*
X210441Y-400933I-494J494D01*
G01*
X218110Y-401427D02*
G03*
X218341Y-400870I-557J557D01*
G01*
X222047Y-401427D02*
G03*
X222641Y-399993I-1433J1433D01*
G01*
X237795Y-401427D02*
G03*
X237941Y-401075I-352J352D01*
G01*
X241732Y-401427D02*
G03*
X241941Y-400923I-504J504D01*
G01*
X273228Y-401427D02*
G03*
X273441Y-400913I-514J514D01*
G01*
X269291Y-401427D02*
G03*
X269441Y-401065I-362J362D01*
G01*
X269370Y-404100D02*
G03*
X269441Y-403929I-171J171D01*
G01*
X218189Y-404100D02*
G03*
X218341Y-403733I-367J367D01*
G01*
X237874Y-404100D02*
G03*
X237941Y-403938I-162J162D01*
G01*
X256941Y-402608D02*
G03*
X257557Y-404098I2110J0D01*
G01*
D02*
G03*
X257559Y-404100I1494J1490D01*
G01*
X218307Y-374706D02*
X218310Y-374444D01*
X218439Y-374114D02*
X218444Y-374109D01*
X218445Y-374108D01*
X218307Y-378873D02*
X218341Y-378907D01*
X218307Y-378873D02*
Y-374706D01*
X222638Y-378904D02*
Y-374655D01*
Y-378904D02*
X222641Y-378907D01*
X206496Y-378774D02*
Y-374655D01*
X210433Y-378899D02*
Y-374655D01*
Y-378899D02*
X210441Y-378907D01*
X269496Y-374321D02*
X269501Y-374292D01*
X269488Y-378793D02*
Y-374409D01*
X269501Y-374292D02*
X269502Y-374291D01*
X273425Y-378891D02*
Y-374655D01*
Y-378891D02*
X273441Y-378907D01*
X237992Y-378783D02*
Y-374655D01*
X241929Y-378895D02*
Y-374655D01*
Y-378895D02*
X241941Y-378907D01*
X253346Y-378679D02*
Y-374879D01*
X256890Y-378783D02*
Y-374655D01*
X273441Y-400913D02*
Y-382293D01*
X269441Y-401065D02*
Y-382293D01*
X256941Y-400125D02*
Y-382293D01*
X253441Y-401180D02*
Y-382293D01*
X206441Y-401085D02*
Y-382293D01*
X210441Y-400933D02*
Y-382293D01*
X218341Y-400870D02*
Y-382293D01*
X222641Y-399993D02*
Y-382293D01*
X237941Y-401075D02*
Y-382293D01*
X241941Y-400923D02*
Y-382293D01*
D72*
X281102Y-401427D02*
D03*
X159055D02*
D03*
X155118D02*
D03*
X186614D02*
D03*
X182677D02*
D03*
X241732D02*
D03*
X273228D02*
D03*
X269291D02*
D03*
X257480D02*
D03*
X237795D02*
D03*
X253543D02*
D03*
X222047D02*
D03*
X218110D02*
D03*
X210236D02*
D03*
X206299D02*
D03*
X190551D02*
D03*
X166929D02*
D03*
X170866D02*
D03*
X174803D02*
D03*
X178740D02*
D03*
X229921D02*
D03*
X214173D02*
D03*
X202362D02*
D03*
X249606D02*
D03*
X265354D02*
D03*
X245669D02*
D03*
X277165D02*
D03*
X261417D02*
D03*
X233858D02*
D03*
X225984D02*
D03*
X162992D02*
D03*
D73*
X151181Y-399477D02*
D03*
D149*
X260561Y-390826D02*
G03*
X259287Y-390247I-1413J-1416D01*
G01*
X215115Y-391673D02*
G03*
X214252Y-393318I1137J-1645D01*
G01*
X555364Y-249410D02*
X568159Y-262205D01*
X634646D01*
X644488Y-252362D01*
X581348Y-253150D02*
X636221D01*
Y-251181D01*
X564896Y-236697D02*
X581348Y-253150D01*
X159134Y-404100D02*
Y-390901D01*
X156441Y-388208D02*
X159134Y-390901D01*
X155197Y-389452D02*
X156441Y-388208D01*
X155197Y-404100D02*
Y-389452D01*
X163071Y-404100D02*
Y-390730D01*
X277289Y-404055D02*
Y-401303D01*
X259285Y-390247D02*
X259287Y-390247D01*
X260561Y-390826D02*
X260562Y-390828D01*
X226063Y-404100D02*
Y-390722D01*
X233937Y-404100D02*
Y-391623D01*
X214252Y-393318D02*
Y-393318D01*
Y-404100D02*
Y-393318D01*
X202441Y-404100D02*
Y-390600D01*
X260562Y-390828D02*
X261343Y-391608D01*
X215115Y-391673D02*
X216162Y-390947D01*
X233937Y-391623D02*
X235144Y-390416D01*
X251378Y-390009D02*
X251456D01*
X277387Y-392067D02*
X279445Y-390009D01*
X281201D01*
X264954Y-401027D02*
Y-392780D01*
X249730Y-391658D02*
X251378Y-390009D01*
X245669Y-391181D02*
X246841Y-390009D01*
X263783Y-391608D02*
X264954Y-392780D01*
X277289Y-401303D02*
X277387Y-401205D01*
X264954Y-401027D02*
X265354Y-401427D01*
X245669D02*
Y-391181D01*
X246841Y-390009D02*
X251378D01*
X261343Y-401353D02*
X261417Y-401427D01*
X261343Y-401353D02*
Y-391608D01*
X263783D01*
X277387Y-401205D02*
Y-392067D01*
X277244Y-404100D02*
X277289Y-404055D01*
X249730Y-401303D02*
Y-391658D01*
X249606Y-401427D02*
X249730Y-401303D01*
X277165Y-401427D02*
X277289Y-401303D01*
X186571Y-403978D02*
Y-389966D01*
X182941Y-386336D02*
X186571Y-389966D01*
X182677Y-389616D02*
X182677Y-389616D01*
Y-401427D02*
Y-389616D01*
X186571Y-403978D02*
X186693Y-404100D01*
D153*
X544291Y-195718D02*
Y-113189D01*
X508858Y-77756D02*
X544291Y-113189D01*
X205709Y-77756D02*
X508858D01*
X158465Y-30512D02*
X205709Y-77756D01*
X66929Y-30512D02*
X158465D01*
X60039Y-37402D02*
X66929Y-30512D01*
X60039Y-70866D02*
Y-37402D01*
Y-70866D02*
X63976Y-74803D01*
X92884Y-92175D02*
X104528D01*
X75512Y-74803D02*
X92884Y-92175D01*
X63976Y-74803D02*
X75512D01*
X104528Y-92283D02*
Y-92175D01*
D157*
X142362Y-120079D02*
D03*
X152362D02*
D03*
X162362D02*
D03*
X579055Y13937D02*
D03*
X569055D02*
D03*
X559055D02*
D03*
X549055D02*
D03*
X539055D02*
D03*
X589055Y3937D02*
D03*
X579055D02*
D03*
X569055D02*
D03*
X559055D02*
D03*
X549055D02*
D03*
X539055D02*
D03*
D158*
X172362Y-120079D02*
D03*
X589055Y13937D02*
D03*
D159*
X258472Y-327165D02*
D03*
X282283D02*
D03*
X294094D02*
D03*
X302362Y-156693D02*
D03*
Y-316535D02*
D03*
X142520D02*
D03*
Y-236614D02*
D03*
Y-156693D02*
D03*
X270472Y-327165D02*
D03*
X246472D02*
D03*
D160*
X674409Y-194488D02*
D03*
Y-161417D02*
D03*
X348211Y-89891D02*
D03*
X357798Y-89963D02*
D03*
D161*
X645669Y-194488D02*
D03*
X624016D02*
D03*
Y-177953D02*
D03*
X645669D02*
D03*
X624016Y-161417D02*
D03*
X645669D02*
D03*
D162*
X391545Y-160477D02*
D03*
X470285D02*
D03*
X528395Y-194680D02*
D03*
Y-273420D02*
D03*
X470275Y-308597D02*
D03*
X391535D02*
D03*
X340904Y-273410D02*
D03*
Y-194670D02*
D03*
D163*
X604291Y-330039D02*
D03*
X574291D02*
D03*
D164*
X-18464Y-326781D02*
D03*
X1535D02*
D03*
Y-306781D02*
D03*
X-18464D02*
D03*
X-18465Y-273630D02*
D03*
X1535D02*
D03*
Y-253630D02*
D03*
X-18465D02*
D03*
Y-220480D02*
D03*
X1535D02*
D03*
Y-200480D02*
D03*
X-18465D02*
D03*
X-18464Y-167332D02*
D03*
X1535D02*
D03*
Y-147332D02*
D03*
X-18464D02*
D03*
D165*
X-8465Y-316781D02*
D03*
X-8465Y-263630D02*
D03*
Y-210480D02*
D03*
X-8465Y-157332D02*
D03*
D166*
X0Y0D02*
D03*
X0Y-378395D02*
D03*
X685039Y0D02*
D03*
X685039Y-340551D02*
D03*
X486221Y-340551D02*
D03*
D167*
X416835Y-196581D02*
D03*
X411811Y-196850D02*
D03*
X593307Y-127953D02*
D03*
X570866Y-70472D02*
D03*
Y-72441D02*
D03*
Y-74410D02*
D03*
X574016Y-70472D02*
D03*
Y-72441D02*
D03*
Y-74410D02*
D03*
X350787Y-116929D02*
D03*
X352756D02*
D03*
X354724D02*
D03*
X350787Y-113779D02*
D03*
X352756D02*
D03*
X354724D02*
D03*
X379134Y-137795D02*
D03*
X375984Y-120079D02*
D03*
X375532Y-123610D02*
D03*
X314658Y-244775D02*
D03*
X315097Y-235081D02*
D03*
X315226Y-230634D02*
D03*
X314864Y-227997D02*
D03*
X314503Y-225180D02*
D03*
X288583Y-225590D02*
D03*
X288189Y-228740D02*
D03*
Y-231102D02*
D03*
X288057Y-233478D02*
D03*
X288057Y-245095D02*
D03*
X288189Y-247638D02*
D03*
X287941Y-241819D02*
D03*
X288189Y-235827D02*
D03*
X588976Y-302756D02*
D03*
X579528Y-303150D02*
D03*
X615748Y-305512D02*
D03*
X562598Y-306693D02*
D03*
X330709Y-120473D02*
D03*
Y-123425D02*
D03*
X121063Y-263632D02*
D03*
X375590Y-127165D02*
D03*
X106299Y-263632D02*
D03*
X330709Y-126378D02*
D03*
X600000Y-146063D02*
D03*
X598032D02*
D03*
X596063D02*
D03*
X587008D02*
D03*
X585039D02*
D03*
X583071D02*
D03*
X575984Y-145669D02*
D03*
X574016D02*
D03*
X572047D02*
D03*
X593307Y-131102D02*
D03*
X595276D02*
D03*
X597244D02*
D03*
X595276Y-127953D02*
D03*
X597244D02*
D03*
X650787Y-229921D02*
D03*
X645669Y-230315D02*
D03*
X641732D02*
D03*
X638189D02*
D03*
X640945Y-250394D02*
D03*
Y-248425D02*
D03*
Y-246457D02*
D03*
X637795Y-250394D02*
D03*
Y-248425D02*
D03*
Y-246457D02*
D03*
X654724Y-211417D02*
D03*
X656693D02*
D03*
X658661D02*
D03*
X654724Y-208268D02*
D03*
X656693D02*
D03*
X658661D02*
D03*
X675591Y-298819D02*
D03*
X673622D02*
D03*
X671654D02*
D03*
X675591Y-301969D02*
D03*
X673622D02*
D03*
X671654D02*
D03*
X157480Y-358661D02*
D03*
X155512D02*
D03*
X153543D02*
D03*
X157480Y-361811D02*
D03*
X155512D02*
D03*
X153543D02*
D03*
X154724Y-389616D02*
D03*
X156693D02*
D03*
X158661D02*
D03*
X154724Y-386466D02*
D03*
X156693D02*
D03*
X158661D02*
D03*
X575919Y-236906D02*
D03*
X596702Y-247441D02*
D03*
X591978D02*
D03*
X586466D02*
D03*
X580954Y-207189D02*
D03*
X580935Y-237412D02*
D03*
X554519Y-212889D02*
D03*
X546419Y-246106D02*
D03*
X626819Y-244005D02*
D03*
X611094Y-248110D02*
D03*
X603002Y-247441D02*
D03*
X531496Y-262647D02*
D03*
X461811Y-310679D02*
D03*
X450000Y-293750D02*
D03*
X422441Y-293789D02*
D03*
X531496Y-213435D02*
D03*
X338525Y-243567D02*
D03*
X525591Y-233088D02*
D03*
X439697Y-162549D02*
D03*
X343144Y-225173D02*
D03*
X420669Y-157923D02*
D03*
X531496Y-223277D02*
D03*
X338583Y-235236D02*
D03*
X525591Y-242962D02*
D03*
X430150Y-162253D02*
D03*
X343444Y-215373D02*
D03*
X432283Y-293750D02*
D03*
X410528Y-157923D02*
D03*
X342944Y-264473D02*
D03*
X444095Y-293750D02*
D03*
X422835Y-311072D02*
D03*
X531496Y-233088D02*
D03*
X430150Y-157923D02*
D03*
X338444Y-225173D02*
D03*
X402756Y-311072D02*
D03*
X525591Y-253969D02*
D03*
X420079Y-162549D02*
D03*
X343403Y-205651D02*
D03*
X525591Y-203592D02*
D03*
X400295Y-157824D02*
D03*
X343144Y-254773D02*
D03*
X431928Y-311189D02*
D03*
X531496Y-242962D02*
D03*
X338844Y-215273D02*
D03*
X402362Y-293750D02*
D03*
X525591Y-262647D02*
D03*
X410913Y-162758D02*
D03*
X338444Y-264473D02*
D03*
X456299Y-293750D02*
D03*
X437795Y-293750D02*
D03*
X525591Y-213435D02*
D03*
X459319Y-162510D02*
D03*
Y-157922D02*
D03*
X342744Y-243747D02*
D03*
X412598Y-311072D02*
D03*
X531496Y-253969D02*
D03*
X449803Y-157923D02*
D03*
X338744Y-205473D02*
D03*
X531496Y-203592D02*
D03*
X401279Y-162509D02*
D03*
X439961Y-157923D02*
D03*
X338444Y-254773D02*
D03*
X461417Y-293750D02*
D03*
X525591Y-223277D02*
D03*
X449508Y-162549D02*
D03*
X343504Y-235236D02*
D03*
X412205Y-293750D02*
D03*
X639750Y-314581D02*
D03*
X658647Y-314581D02*
D03*
X509405Y-345138D02*
D03*
X509011Y-330177D02*
D03*
X56441Y-143600D02*
D03*
Y-151600D02*
D03*
Y-191600D02*
D03*
Y-199600D02*
D03*
Y-215600D02*
D03*
Y-223600D02*
D03*
Y-231600D02*
D03*
Y-247600D02*
D03*
Y-255600D02*
D03*
Y-271600D02*
D03*
Y-279600D02*
D03*
Y-287600D02*
D03*
Y-303600D02*
D03*
Y-311600D02*
D03*
Y-327600D02*
D03*
Y-335600D02*
D03*
Y-343600D02*
D03*
Y-351600D02*
D03*
X54441Y-139600D02*
D03*
X52441Y-143600D02*
D03*
X54441Y-147600D02*
D03*
X52441Y-151600D02*
D03*
Y-191600D02*
D03*
X54441Y-195600D02*
D03*
X52441Y-199600D02*
D03*
X54441Y-203600D02*
D03*
X52441Y-215600D02*
D03*
X54441Y-219600D02*
D03*
X52441Y-223600D02*
D03*
X54441Y-227600D02*
D03*
X52441Y-231600D02*
D03*
X54441Y-235600D02*
D03*
Y-243600D02*
D03*
X52441Y-247600D02*
D03*
X54441Y-251600D02*
D03*
X52441Y-255600D02*
D03*
X54441Y-267600D02*
D03*
X52441Y-271600D02*
D03*
X54441Y-275600D02*
D03*
X52441Y-279600D02*
D03*
Y-287600D02*
D03*
X54441Y-291600D02*
D03*
Y-299600D02*
D03*
X52441Y-303600D02*
D03*
X54441Y-307600D02*
D03*
X52441Y-311600D02*
D03*
X54441Y-323600D02*
D03*
X52441Y-327600D02*
D03*
X54441Y-331600D02*
D03*
X52441Y-335600D02*
D03*
X54441Y-339600D02*
D03*
X52441Y-343600D02*
D03*
Y-351600D02*
D03*
X50441Y-139600D02*
D03*
X48441Y-143600D02*
D03*
X50441Y-195600D02*
D03*
X48441Y-199600D02*
D03*
Y-223600D02*
D03*
X50441Y-227600D02*
D03*
X48441Y-231600D02*
D03*
X50441Y-235600D02*
D03*
Y-243600D02*
D03*
X48441Y-247600D02*
D03*
X50441Y-251600D02*
D03*
Y-275600D02*
D03*
X48441Y-279600D02*
D03*
Y-287600D02*
D03*
X50441Y-291600D02*
D03*
Y-299600D02*
D03*
X48441Y-303600D02*
D03*
X50441Y-331600D02*
D03*
X48441Y-335600D02*
D03*
X50441Y-339600D02*
D03*
X48441Y-343600D02*
D03*
Y-351600D02*
D03*
X46441Y-139600D02*
D03*
X44441Y-143600D02*
D03*
X46441Y-227600D02*
D03*
X44441Y-231600D02*
D03*
X46441Y-235600D02*
D03*
Y-243600D02*
D03*
X44441Y-247600D02*
D03*
Y-279600D02*
D03*
Y-287600D02*
D03*
X46441Y-291600D02*
D03*
Y-299600D02*
D03*
Y-331600D02*
D03*
X44441Y-335600D02*
D03*
X46441Y-339600D02*
D03*
X44441Y-343600D02*
D03*
Y-351600D02*
D03*
X42441Y-139600D02*
D03*
X40441Y-143600D02*
D03*
Y-223600D02*
D03*
X42441Y-227600D02*
D03*
X40441Y-231600D02*
D03*
X42441Y-235600D02*
D03*
Y-243600D02*
D03*
X40441Y-247600D02*
D03*
X42441Y-299600D02*
D03*
Y-331600D02*
D03*
X40441Y-335600D02*
D03*
X42441Y-339600D02*
D03*
X40441Y-343600D02*
D03*
Y-351600D02*
D03*
X38441Y-139600D02*
D03*
X36441Y-143600D02*
D03*
Y-151600D02*
D03*
Y-215600D02*
D03*
Y-223600D02*
D03*
X38441Y-227600D02*
D03*
X36441Y-231600D02*
D03*
X38441Y-235600D02*
D03*
Y-243600D02*
D03*
X36441Y-247600D02*
D03*
X38441Y-251600D02*
D03*
X36441Y-255600D02*
D03*
Y-327600D02*
D03*
X38441Y-331600D02*
D03*
X36441Y-335600D02*
D03*
X38441Y-339600D02*
D03*
X36441Y-343600D02*
D03*
Y-351600D02*
D03*
X34441Y-139600D02*
D03*
X32441Y-143600D02*
D03*
X34441Y-147600D02*
D03*
X32441Y-151600D02*
D03*
X34441Y-163600D02*
D03*
Y-219600D02*
D03*
Y-227600D02*
D03*
Y-235600D02*
D03*
Y-243600D02*
D03*
Y-251600D02*
D03*
Y-267600D02*
D03*
Y-275600D02*
D03*
Y-299600D02*
D03*
Y-307600D02*
D03*
Y-323600D02*
D03*
X32441Y-327600D02*
D03*
X34441Y-331600D02*
D03*
X32441Y-335600D02*
D03*
X34441Y-339600D02*
D03*
X32441Y-343600D02*
D03*
Y-351600D02*
D03*
X30441Y-139600D02*
D03*
X28441Y-143600D02*
D03*
X30441Y-147600D02*
D03*
X28441Y-151600D02*
D03*
X30441Y-163600D02*
D03*
X28441Y-167600D02*
D03*
Y-327600D02*
D03*
X30441Y-331600D02*
D03*
X28441Y-335600D02*
D03*
X30441Y-339600D02*
D03*
X28441Y-343600D02*
D03*
Y-351600D02*
D03*
X26441Y-139600D02*
D03*
X24441Y-143600D02*
D03*
X26441Y-147600D02*
D03*
X24441Y-151600D02*
D03*
X26441Y-163600D02*
D03*
X24441Y-167600D02*
D03*
Y-191600D02*
D03*
X26441Y-195600D02*
D03*
X24441Y-287600D02*
D03*
X26441Y-299600D02*
D03*
X24441Y-303600D02*
D03*
X26441Y-307600D02*
D03*
X24441Y-311600D02*
D03*
X26441Y-331600D02*
D03*
X24441Y-335600D02*
D03*
X26441Y-339600D02*
D03*
X24441Y-343600D02*
D03*
Y-351600D02*
D03*
X22441Y-139600D02*
D03*
X20441Y-143600D02*
D03*
X22441Y-147600D02*
D03*
X20441Y-151600D02*
D03*
X22441Y-163600D02*
D03*
X20441Y-167600D02*
D03*
X22441Y-171600D02*
D03*
X20441Y-191600D02*
D03*
X22441Y-195600D02*
D03*
X20441Y-199600D02*
D03*
Y-231600D02*
D03*
X22441Y-235600D02*
D03*
Y-243600D02*
D03*
X20441Y-247600D02*
D03*
X22441Y-251600D02*
D03*
X20441Y-255600D02*
D03*
X22441Y-259600D02*
D03*
Y-267600D02*
D03*
X20441Y-271600D02*
D03*
X22441Y-283600D02*
D03*
X20441Y-287600D02*
D03*
X22441Y-291600D02*
D03*
Y-299600D02*
D03*
X20441Y-303600D02*
D03*
X22441Y-307600D02*
D03*
X20441Y-311600D02*
D03*
X22441Y-323600D02*
D03*
X20441Y-335600D02*
D03*
X22441Y-339600D02*
D03*
X20441Y-343600D02*
D03*
Y-351600D02*
D03*
X18441Y-139600D02*
D03*
X16441Y-143600D02*
D03*
X18441Y-147600D02*
D03*
X16441Y-151600D02*
D03*
X18441Y-163600D02*
D03*
X16441Y-167600D02*
D03*
X18441Y-171600D02*
D03*
X16441Y-191600D02*
D03*
X18441Y-195600D02*
D03*
X16441Y-199600D02*
D03*
X18441Y-203600D02*
D03*
X16441Y-215600D02*
D03*
X18441Y-219600D02*
D03*
X16441Y-223600D02*
D03*
X18441Y-235600D02*
D03*
Y-243600D02*
D03*
X16441Y-247600D02*
D03*
X18441Y-251600D02*
D03*
X16441Y-255600D02*
D03*
X18441Y-259600D02*
D03*
Y-267600D02*
D03*
X16441Y-271600D02*
D03*
X18441Y-275600D02*
D03*
X16441Y-279600D02*
D03*
X18441Y-291600D02*
D03*
Y-299600D02*
D03*
X16441Y-303600D02*
D03*
X18441Y-307600D02*
D03*
X16441Y-311600D02*
D03*
X18441Y-323600D02*
D03*
X16441Y-327600D02*
D03*
X18441Y-339600D02*
D03*
X16441Y-343600D02*
D03*
Y-351600D02*
D03*
X14441Y-139600D02*
D03*
X12441Y-143600D02*
D03*
X14441Y-147600D02*
D03*
X12441Y-151600D02*
D03*
X14441Y-163600D02*
D03*
X12441Y-167600D02*
D03*
X14441Y-171600D02*
D03*
X12441Y-191600D02*
D03*
X14441Y-195600D02*
D03*
X12441Y-199600D02*
D03*
X14441Y-203600D02*
D03*
X12441Y-215600D02*
D03*
X14441Y-219600D02*
D03*
X12441Y-223600D02*
D03*
X14441Y-243600D02*
D03*
X12441Y-247600D02*
D03*
X14441Y-251600D02*
D03*
X12441Y-255600D02*
D03*
X14441Y-259600D02*
D03*
Y-267600D02*
D03*
X12441Y-271600D02*
D03*
X14441Y-275600D02*
D03*
X12441Y-279600D02*
D03*
X14441Y-291600D02*
D03*
Y-299600D02*
D03*
X12441Y-303600D02*
D03*
X14441Y-307600D02*
D03*
X12441Y-311600D02*
D03*
X14441Y-323600D02*
D03*
X12441Y-327600D02*
D03*
X14441Y-331600D02*
D03*
X12441Y-343600D02*
D03*
Y-351600D02*
D03*
X10441Y-139600D02*
D03*
Y-163600D02*
D03*
Y-171600D02*
D03*
X8441Y-191600D02*
D03*
X10441Y-195600D02*
D03*
Y-203600D02*
D03*
Y-227600D02*
D03*
Y-243600D02*
D03*
X8441Y-247600D02*
D03*
X10441Y-251600D02*
D03*
Y-259600D02*
D03*
Y-267600D02*
D03*
Y-275600D02*
D03*
X8441Y-279600D02*
D03*
X10441Y-299600D02*
D03*
Y-323600D02*
D03*
Y-331600D02*
D03*
X8441Y-351600D02*
D03*
X6441Y-139600D02*
D03*
X4441Y-191600D02*
D03*
X6441Y-243600D02*
D03*
X4441Y-351600D02*
D03*
X2441Y-243600D02*
D03*
X441Y-351600D02*
D03*
X-3559Y-191600D02*
D03*
X-1559Y-243600D02*
D03*
X-3559Y-351600D02*
D03*
X-5559Y-139600D02*
D03*
X-7559Y-143600D02*
D03*
Y-167600D02*
D03*
Y-191600D02*
D03*
Y-199600D02*
D03*
Y-223600D02*
D03*
X-5559Y-227600D02*
D03*
Y-243600D02*
D03*
X-7559Y-247600D02*
D03*
Y-279600D02*
D03*
X-5559Y-299600D02*
D03*
X-7559Y-303600D02*
D03*
Y-327600D02*
D03*
Y-351600D02*
D03*
X-9559Y-139600D02*
D03*
Y-171600D02*
D03*
X-11559Y-191600D02*
D03*
X-9559Y-195600D02*
D03*
Y-227600D02*
D03*
Y-243600D02*
D03*
X-11559Y-247600D02*
D03*
X-9559Y-251600D02*
D03*
Y-275600D02*
D03*
X-11559Y-279600D02*
D03*
X-9559Y-299600D02*
D03*
Y-331600D02*
D03*
X-11559Y-351600D02*
D03*
X-13559Y-139600D02*
D03*
X-15559Y-191600D02*
D03*
X-13559Y-243600D02*
D03*
X-15559Y-351600D02*
D03*
X-19559Y-263600D02*
D03*
Y-351600D02*
D03*
X-23559Y-159600D02*
D03*
Y-191600D02*
D03*
X-21559Y-211600D02*
D03*
X-23559Y-263600D02*
D03*
X-21559Y-315600D02*
D03*
X-23559Y-351600D02*
D03*
X-25559Y-139600D02*
D03*
Y-155600D02*
D03*
Y-211600D02*
D03*
Y-259600D02*
D03*
Y-267600D02*
D03*
Y-299600D02*
D03*
Y-315600D02*
D03*
X269685Y-136843D02*
D03*
X234252Y-133742D02*
D03*
X263779Y-106151D02*
D03*
X71850Y-147638D02*
D03*
X75787Y-131890D02*
D03*
X643701Y-63976D02*
D03*
X644685Y-45276D02*
D03*
X623000Y-37402D02*
D03*
X610236Y-8858D02*
D03*
X609252Y-26575D02*
D03*
X98425Y-102362D02*
D03*
X89567D02*
D03*
X85630Y-313976D02*
D03*
X86614Y-258858D02*
D03*
X81693Y-205709D02*
D03*
X86614Y-110236D02*
D03*
X360236Y-268586D02*
D03*
Y-272490D02*
D03*
X63976Y-227362D02*
D03*
X68898Y-285433D02*
D03*
X67913Y-340551D02*
D03*
X68573Y-179321D02*
D03*
X44291Y-252953D02*
D03*
Y-272638D02*
D03*
Y-326772D02*
D03*
Y-307087D02*
D03*
X26575Y-291339D02*
D03*
X31496Y-189961D02*
D03*
X44291Y-147638D02*
D03*
Y-167323D02*
D03*
Y-200787D02*
D03*
Y-220472D02*
D03*
X570727Y-105662D02*
D03*
X325787Y-243205D02*
D03*
Y-233362D02*
D03*
X103409Y-141732D02*
D03*
X103347Y-110236D02*
D03*
X119095Y-126047D02*
D03*
X494095Y-137647D02*
D03*
X518701Y-104214D02*
D03*
X519587Y-134596D02*
D03*
X528543Y-104214D02*
D03*
X625000Y-48080D02*
D03*
X658465Y-21899D02*
D03*
X625000Y-29773D02*
D03*
X114173Y-83088D02*
D03*
X441929Y-122883D02*
D03*
X256890Y-124852D02*
D03*
Y-121899D02*
D03*
X250000Y-120915D02*
D03*
X129921Y-79576D02*
D03*
X473425Y-125836D02*
D03*
X473425Y-123868D02*
D03*
X473425Y-121899D02*
D03*
X505905Y-137647D02*
D03*
X163071Y-390730D02*
D03*
X632432Y-132480D02*
D03*
X614321Y-118307D02*
D03*
X99410Y-50049D02*
D03*
X26495Y-8991D02*
D03*
X512657Y-270462D02*
D03*
X632432Y-141142D02*
D03*
X259285Y-390247D02*
D03*
X267204Y-390009D02*
D03*
X216162Y-390947D02*
D03*
X235144Y-390416D02*
D03*
X251456Y-390009D02*
D03*
X226063Y-390722D02*
D03*
X281201Y-390009D02*
D03*
X174941Y-390600D02*
D03*
X202441D02*
D03*
X538813Y-144506D02*
D03*
X544813Y-109806D02*
D03*
X566813Y-132405D02*
D03*
X555364Y-249410D02*
D03*
X544291Y-199655D02*
D03*
X509842Y-197687D02*
D03*
X544291Y-201624D02*
D03*
X509842Y-199655D02*
D03*
Y-201624D02*
D03*
X544291Y-197687D02*
D03*
X509842Y-195718D02*
D03*
X361811Y-207087D02*
D03*
X361417Y-203150D02*
D03*
X326969Y-197573D02*
D03*
X326966Y-195171D02*
D03*
X366535Y-202362D02*
D03*
X358661Y-194488D02*
D03*
X634252Y-314567D02*
D03*
X653150Y-314567D02*
D03*
X509391Y-350636D02*
D03*
X508997Y-335675D02*
D03*
X237402Y-133465D02*
D03*
X240945D02*
D03*
X447244Y-324852D02*
D03*
X451181D02*
D03*
X433858D02*
D03*
X460630D02*
D03*
X437795D02*
D03*
X431102D02*
D03*
X444488D02*
D03*
X457480D02*
D03*
X453937D02*
D03*
X440551D02*
D03*
X222638Y-374655D02*
D03*
X218445Y-374108D02*
D03*
X453937Y-306742D02*
D03*
X451181D02*
D03*
X267286Y-130697D02*
D03*
X109409Y-140111D02*
D03*
X105409D02*
D03*
X101409D02*
D03*
X97409D02*
D03*
X399618Y-136828D02*
D03*
X65945Y-57923D02*
D03*
X615158Y-8858D02*
D03*
X70866Y-122047D02*
D03*
X360204Y-252984D02*
D03*
X417596Y-175197D02*
D03*
X377921Y-203740D02*
D03*
X372016Y-200787D02*
D03*
X354541Y-223636D02*
D03*
X354452Y-235236D02*
D03*
X356578Y-225247D02*
D03*
X379921Y-201740D02*
D03*
X102528Y-211583D02*
D03*
X97125Y-219488D02*
D03*
X99410Y-216535D02*
D03*
X101378Y-214567D02*
D03*
X86614Y-175197D02*
D03*
X361652Y-235205D02*
D03*
X359131Y-223425D02*
D03*
X361531D02*
D03*
X360236Y-262186D02*
D03*
Y-266186D02*
D03*
X85416Y-317699D02*
D03*
X85630Y-263779D02*
D03*
X86562Y-211183D02*
D03*
X411043Y-174974D02*
D03*
X413440Y-174850D02*
D03*
X421596Y-175034D02*
D03*
X406528Y-157767D02*
D03*
X404528Y-163386D02*
D03*
X407480Y-160433D02*
D03*
X86614Y-221457D02*
D03*
X427165Y-175246D02*
D03*
X75787Y-232283D02*
D03*
X87167Y-166377D02*
D03*
X89567Y-166370D02*
D03*
X85630Y-213583D02*
D03*
Y-266179D02*
D03*
Y-320313D02*
D03*
X543276Y-226591D02*
D03*
X544294Y-224248D02*
D03*
X544291Y-233268D02*
D03*
X359252Y-235236D02*
D03*
X356852D02*
D03*
X407480Y-163386D02*
D03*
X47244Y-8858D02*
D03*
X40354D02*
D03*
X33465D02*
D03*
X26575Y19685D02*
D03*
X86614Y-227362D02*
D03*
X63976Y-221457D02*
D03*
X82677Y-232283D02*
D03*
X63976Y-275590D02*
D03*
X75787Y-285433D02*
D03*
X87598Y-275590D02*
D03*
Y-281496D02*
D03*
X81880Y-287582D02*
D03*
X62992Y-329724D02*
D03*
X74803Y-339567D02*
D03*
X78740Y-340551D02*
D03*
X87598Y-335630D02*
D03*
Y-329724D02*
D03*
X63976Y-179134D02*
D03*
X74803D02*
D03*
X86562Y-169257D02*
D03*
X80709Y-180118D02*
D03*
X26575Y-283465D02*
D03*
X30512Y-170276D02*
D03*
X323850Y-241173D02*
D03*
Y-237205D02*
D03*
X323819Y-231299D02*
D03*
X325787Y-229362D02*
D03*
X323819Y-227362D02*
D03*
X325787Y-239205D02*
D03*
X-23622Y-342520D02*
D03*
X89567Y-140270D02*
D03*
X87254Y-139629D02*
D03*
X119095Y-130047D02*
D03*
X117126Y-132047D02*
D03*
X107346Y-110236D02*
D03*
X105347Y-112205D02*
D03*
X99347Y-110236D02*
D03*
X109409Y-112236D02*
D03*
X119095Y-122047D02*
D03*
X-23622Y-229331D02*
D03*
Y-233268D02*
D03*
Y-237205D02*
D03*
Y-241142D02*
D03*
Y-282480D02*
D03*
Y-286417D02*
D03*
Y-290354D02*
D03*
Y-294291D02*
D03*
Y-335630D02*
D03*
Y-339567D02*
D03*
Y-346457D02*
D03*
X107409Y-141732D02*
D03*
X99410D02*
D03*
X-23622Y-70866D02*
D03*
Y-66929D02*
D03*
Y-62992D02*
D03*
Y-60039D02*
D03*
Y-102362D02*
D03*
Y-106299D02*
D03*
Y-110236D02*
D03*
Y-114173D02*
D03*
Y-187992D02*
D03*
Y-184055D02*
D03*
Y-181102D02*
D03*
Y-177165D02*
D03*
X117126Y-128047D02*
D03*
Y-124047D02*
D03*
Y-119921D02*
D03*
X101284Y-112205D02*
D03*
X97284D02*
D03*
X544291Y-195718D02*
D03*
X469521Y-137615D02*
D03*
X533878Y-117716D02*
D03*
X524606Y-125836D02*
D03*
X524557Y-128740D02*
D03*
X651557Y-64306D02*
D03*
X450850Y-174127D02*
D03*
X512795Y-104214D02*
D03*
X320866Y-272490D02*
D03*
X463551Y-116025D02*
D03*
X658465Y-37647D02*
D03*
Y-29773D02*
D03*
X625000Y-21899D02*
D03*
X190354Y-377411D02*
D03*
X412339Y-123805D02*
D03*
X424213Y-175246D02*
D03*
X314961Y-118947D02*
D03*
X430807Y-175344D02*
D03*
X309016Y-128659D02*
D03*
X418898Y-144143D02*
D03*
X405512Y-136611D02*
D03*
X416106Y-144180D02*
D03*
X398568Y-145083D02*
D03*
X210433Y-374655D02*
D03*
X206496D02*
D03*
X442126Y-306742D02*
D03*
X439370D02*
D03*
X237992Y-374655D02*
D03*
X241929D02*
D03*
X253655Y-374421D02*
D03*
X256890Y-374655D02*
D03*
X273425D02*
D03*
X269502Y-374291D02*
D03*
X246339Y-386975D02*
D03*
X249410Y-387253D02*
D03*
X232480D02*
D03*
X229331D02*
D03*
X436221Y-306742D02*
D03*
X212795Y-387253D02*
D03*
X433465Y-306742D02*
D03*
X215945Y-387253D02*
D03*
X262006Y-387255D02*
D03*
X448032Y-306742D02*
D03*
X265158Y-387253D02*
D03*
X445276Y-306742D02*
D03*
X104528Y-92175D02*
D03*
X269685Y-106151D02*
D03*
X244094Y-109104D02*
D03*
X475295Y-133612D02*
D03*
X505905Y-131742D02*
D03*
X131890Y-72687D02*
D03*
X179134Y-386466D02*
D03*
Y-389616D02*
D03*
X178543Y-377411D02*
D03*
X534400Y-126969D02*
D03*
X443898Y-175049D02*
D03*
X99410Y-65797D02*
D03*
Y-57923D02*
D03*
X65945Y-65797D02*
D03*
Y-50049D02*
D03*
X78740Y-238041D02*
D03*
X33465Y19833D02*
D03*
X40354Y19685D02*
D03*
X47244D02*
D03*
X483268Y-114025D02*
D03*
X492319Y-114970D02*
D03*
X487205Y-114057D02*
D03*
X456742Y-116043D02*
D03*
X464328Y-146397D02*
D03*
X469291Y-143848D02*
D03*
X461319Y-143750D02*
D03*
X267323Y-122883D02*
D03*
X457283Y-175147D02*
D03*
X469390D02*
D03*
X544291Y-215403D02*
D03*
X512402Y-261958D02*
D03*
Y-265108D02*
D03*
X512543Y-268065D02*
D03*
X437697Y-175246D02*
D03*
X433858D02*
D03*
X404823Y-175344D02*
D03*
X402264D02*
D03*
X237008Y-129576D02*
D03*
X309016Y-113986D02*
D03*
X193898Y-115009D02*
D03*
Y-119931D02*
D03*
X309055Y-123868D02*
D03*
X182677Y-386466D02*
D03*
X186614D02*
D03*
X182677Y-389616D02*
D03*
X186614D02*
D03*
D168*
X611417Y-227953D02*
D03*
Y-223228D02*
D03*
X604724Y-227953D02*
D03*
X598819Y-228346D02*
D03*
X604724Y-222835D02*
D03*
X599065Y-223031D02*
D03*
X576132Y-124606D02*
D03*
D169*
X564896Y-236697D02*
D03*
D170*
X651545Y-95108D02*
D03*
X413356Y7254D02*
D03*
Y-95108D02*
D03*
X651545Y7254D02*
D03*
X71880Y7412D02*
D03*
X310069Y-94950D02*
D03*
Y7412D02*
D03*
X71880Y-94950D02*
D03*
D171*
X99016Y-121653D02*
D03*
X103347D02*
D03*
X107677D02*
D03*
X99016Y-125984D02*
D03*
X103347D02*
D03*
X107677D02*
D03*
X99016Y-130315D02*
D03*
X103347D02*
D03*
X107677D02*
D03*
D172*
X218189Y-404100D02*
D03*
D173*
X273441Y-382293D02*
D03*
Y-378907D02*
D03*
X206441D02*
D03*
Y-382293D02*
D03*
X210441D02*
D03*
Y-378907D02*
D03*
X218341D02*
D03*
Y-382293D02*
D03*
X222641D02*
D03*
Y-378907D02*
D03*
X237941Y-382293D02*
D03*
Y-378907D02*
D03*
X241941Y-382293D02*
D03*
Y-378907D02*
D03*
X253441Y-382293D02*
D03*
Y-378907D02*
D03*
X256941D02*
D03*
Y-382293D02*
D03*
X269441D02*
D03*
Y-378907D02*
D03*
D174*
X669291Y-304331D02*
X673622Y-300000D01*
X653543Y-304331D02*
X669291D01*
X638189Y-288976D02*
X653543Y-304331D01*
X519291Y-288976D02*
X638189D01*
X155512Y-361811D02*
Y-359959D01*
X169014Y-346457D02*
X451575D01*
X155512Y-359959D02*
X169014Y-346457D01*
X451575D02*
X502756Y-295276D01*
X512992D01*
X519291Y-288976D01*
D175*
X156644Y-388287D02*
D03*
X184518Y-388354D02*
D03*
M02*
